# Altium SchDoc records: USER_IO_STATUS.SchDoc
|HEADER=Protel for Windows - Schematic Capture Binary File Version 5.0|Weight=911|MinorVersion=2
|RECORD=31|FontIdCount=8|Size1=10|FontName1=Times New Roman|Size2=8|FontName2=Arial|Size3=10|FontName3=Arial|Size4=12|Underline4=T|FontName4=Arial|Size5=24|FontName5=Times New Roman|Size6=10|Underline6=T|FontName6=Times New Roman|Size7=14|FontName7=Times New Roman|Size8=11|FontName8=Arial|UseMBCS=T|IsBOC=T|HotSpotGridOn=T|HotSpotGridSize=2|SheetStyle=12|SystemFont=3|BorderOn=T|SheetNumberSpaceSize=12|AreaColor=16317695|SnapGridOn=T|SnapGridSize=5|VisibleGridOn=T|VisibleGridSize=10|CustomX=2338|CustomX_Frac=58268|CustomY=1653|CustomY_Frac=54331|CustomXZones=8|CustomYZones=6|CustomMarginWidth=19|CustomMarginWidth_Frac=80000|ShowTemplateGraphics=T|TemplateFileName=C:\Users\<user>\Documents\Altium\AD20\Templates\Timecard.SchDot|Display_Unit=0
|RECORD=39|IsNotAccesible=T|OwnerPartId=-1|FileName=C:\Users\<user>\Documents\Altium\AD20\Templates\Timecard.SchDot
|RECORD=4|OwnerIndex=1|OwnerPartId=-1|Location.X=1594|Location.Y=39|Color=8388608|FontID=4|Text=timingcard.com|URL=http://timingcard.com
|RECORD=6|OwnerIndex=1|IndexInSheet=1|OwnerPartId=-1|LocationCount=2|X1=1680|Y1=35|X2=1576|Y2=35
|RECORD=4|OwnerIndex=1|IndexInSheet=2|OwnerPartId=-1|Location.X=1615|Location.Y=27|Justification=4|Color=16711680|FontID=8|Text==SheetNumber
|RECORD=4|OwnerIndex=1|IndexInSheet=3|OwnerPartId=-1|Location.X=1581|Location.X_Frac=42446|Location.Y=29|Location.Y_Frac=96838|Justification=3|FontID=2|Text=SHEET
|RECORD=4|OwnerIndex=1|IndexInSheet=4|OwnerPartId=-1|Location.X=1639|Location.X_Frac=42446|Location.Y=29|Location.Y_Frac=96838|Justification=3|FontID=2|Text=OF
|RECORD=6|OwnerIndex=1|IndexInSheet=5|OwnerPartId=-1|LineWidth=1|LocationCount=2|X1=1679|X1_Frac=42446|Y1=117|Y1_Frac=96838|X2=1576|Y2=118
|RECORD=4|OwnerIndex=1|IndexInSheet=6|OwnerPartId=-1|Location.X=1659|Location.Y=27|Justification=4|Color=16711680|FontID=8|Text==SheetTotal
|RECORD=30|OwnerIndex=1|IndexInSheet=7|OwnerPartId=-1|Location.X=1578|Location.Y=65|Corner.X=1673|Corner.X_Frac=88801|Corner.Y=115|KeepAspect=T|FileName=C:\Users\<user>\Desktop\Timecard Logo\TIMECARD.jpg
|RECORD=6|OwnerIndex=1|IndexInSheet=8|OwnerPartId=-1|LineWidth=1|LocationCount=2|X1=1576|X1_Frac=3162|Y1=117|Y1_Frac=42446|X2=1576|Y2=21
|RECORD=6|OwnerIndex=1|IndexInSheet=9|OwnerPartId=-1|LocationCount=2|X1=1680|Y1=51|X2=1576|Y2=51
|RECORD=4|OwnerIndex=1|IndexInSheet=10|OwnerPartId=-1|Location.X=1581|Location.X_Frac=42446|Location.Y=56|Location.Y_Frac=96838|Justification=3|FontID=2|Text=REV
|RECORD=4|OwnerIndex=1|IndexInSheet=11|OwnerPartId=-1|Location.X=1619|Location.Y=57|Justification=3|FontID=2|Text=DATE
|RECORD=6|OwnerIndex=1|IndexInSheet=12|OwnerPartId=-1|LocationCount=2|X1=1680|Y1=65|X2=1576|Y2=65
|RECORD=4|OwnerIndex=1|IndexInSheet=13|OwnerPartId=-1|Location.X=1605|Location.Y=58|Justification=4|Color=16711680|FontID=8|Text==ProjectRevision
|RECORD=4|OwnerIndex=1|IndexInSheet=14|OwnerPartId=-1|Location.X=1659|Location.Y=58|Justification=4|Color=16711680|FontID=8|Text==ProjectDate
|RECORD=41|IndexInSheet=1|OwnerPartId=-1|Color=8388608|FontID=1|IsHidden=T|Text=*|Name=CurrentTime|ReadOnlyState=1
|RECORD=41|IndexInSheet=2|OwnerPartId=-1|Color=8388608|FontID=1|IsHidden=T|Text=*|Name=CurrentDate|ReadOnlyState=1
|RECORD=41|IndexInSheet=3|OwnerPartId=-1|Color=8388608|FontID=1|IsHidden=T|Text=*|Name=Time|ReadOnlyState=1
|RECORD=41|IndexInSheet=4|OwnerPartId=-1|Color=8388608|FontID=1|IsHidden=T|Text=*|Name=Date|ReadOnlyState=1
|RECORD=41|IndexInSheet=5|OwnerPartId=-1|Color=8388608|FontID=1|IsHidden=T|Text=*|Name=DocumentFullPathAndName|ReadOnlyState=1
|RECORD=41|IndexInSheet=6|OwnerPartId=-1|Color=8388608|FontID=1|IsHidden=T|Text=*|Name=DocumentName|ReadOnlyState=1
|RECORD=41|IndexInSheet=7|OwnerPartId=-1|Color=8388608|FontID=1|IsHidden=T|Text=*|Name=ModifiedDate|ReadOnlyState=1
|RECORD=41|IndexInSheet=8|OwnerPartId=-1|Color=8388608|FontID=1|IsHidden=T|Text=*|Name=ApprovedBy|ReadOnlyState=1
|RECORD=41|IndexInSheet=9|OwnerPartId=-1|Color=8388608|FontID=1|IsHidden=T|Text=*|Name=CheckedBy|ReadOnlyState=1
|RECORD=41|IndexInSheet=10|OwnerPartId=-1|Color=8388608|FontID=1|IsHidden=T|Text=*|Name=Author|ReadOnlyState=1
|RECORD=41|IndexInSheet=11|OwnerPartId=-1|Color=8388608|FontID=1|IsHidden=T|Text=*|Name=CompanyName|ReadOnlyState=1
|RECORD=41|IndexInSheet=12|OwnerPartId=-1|Color=8388608|FontID=1|IsHidden=T|Text=*|Name=DrawnBy|ReadOnlyState=1
|RECORD=41|IndexInSheet=13|OwnerPartId=-1|Color=8388608|FontID=1|IsHidden=T|Text=*|Name=Engineer|ReadOnlyState=1
|RECORD=41|IndexInSheet=14|OwnerPartId=-1|Color=8388608|FontID=1|IsHidden=T|Text=*|Name=Organization|ReadOnlyState=1
|RECORD=41|IndexInSheet=15|OwnerPartId=-1|Color=8388608|FontID=1|IsHidden=T|Text=*|Name=Address1|ReadOnlyState=1
|RECORD=41|IndexInSheet=16|OwnerPartId=-1|Color=8388608|FontID=1|IsHidden=T|Text=*|Name=Address2|ReadOnlyState=1
|RECORD=41|IndexInSheet=17|OwnerPartId=-1|Color=8388608|FontID=1|IsHidden=T|Text=*|Name=Address3|ReadOnlyState=1
|RECORD=41|IndexInSheet=18|OwnerPartId=-1|Color=8388608|FontID=1|IsHidden=T|Text=*|Name=Address4|ReadOnlyState=1
|RECORD=41|IndexInSheet=19|OwnerPartId=-1|Color=8388608|FontID=1|IsHidden=T|Text=*|Name=Title|ReadOnlyState=1
|RECORD=41|IndexInSheet=20|OwnerPartId=-1|Color=8388608|FontID=1|IsHidden=T|Text=2|Name=DocumentNumber|ReadOnlyState=1
|RECORD=41|IndexInSheet=21|OwnerPartId=-1|Color=8388608|FontID=1|IsHidden=T|Text=*|Name=Revision|ReadOnlyState=1
|RECORD=41|IndexInSheet=22|OwnerPartId=-1|Color=8388608|FontID=1|IsHidden=T|Text=2|Name=SheetNumber|ReadOnlyState=1
|RECORD=41|IndexInSheet=23|OwnerPartId=-1|Color=8388608|FontID=1|IsHidden=T|Text=7|Name=SheetTotal|ReadOnlyState=1
|RECORD=41|IndexInSheet=24|OwnerPartId=-1|Color=8388608|FontID=1|IsHidden=T|Text=*|Name=Rule|ReadOnlyState=1
|RECORD=41|IndexInSheet=25|OwnerPartId=-1|Color=8388608|FontID=1|IsHidden=T|Text=*|Name=ImagePath|ReadOnlyState=1
|RECORD=41|IndexInSheet=26|OwnerPartId=-1|Color=8388608|FontID=1|IsHidden=T|Text=*|Name=ProjectName|ReadOnlyState=1
|RECORD=41|IndexInSheet=27|OwnerPartId=-1|Color=8388608|FontID=1|IsHidden=T|Text=*|Name=Application_BuildNumber|ReadOnlyState=1
|RECORD=17|IndexInSheet=28|OwnerPartId=-1|ShowNetName=T|Location.X=1000|Location.Y=930|Orientation=1|Color=128|FontID=1|Text=+3.3V
|RECORD=17|IndexInSheet=29|OwnerPartId=-1|ShowNetName=T|Location.X=900|Location.Y=930|Orientation=1|Color=128|FontID=1|Text=+3.3V
|RECORD=17|IndexInSheet=30|OwnerPartId=-1|ShowNetName=T|Location.X=800|Location.Y=930|Orientation=1|Color=128|FontID=1|Text=+3.3V
|RECORD=17|IndexInSheet=31|OwnerPartId=-1|ShowNetName=T|Location.X=700|Location.Y=925|Orientation=1|Color=128|FontID=1|Text=+3.3V
|RECORD=17|IndexInSheet=32|OwnerPartId=-1|ShowNetName=T|Location.X=690|Location.Y=770|Orientation=2|Color=255|FontID=1|Text=LED1|IsCrossSheetConnector=T
|RECORD=17|IndexInSheet=33|OwnerPartId=-1|ShowNetName=T|Location.X=790|Location.Y=770|Orientation=2|Color=255|FontID=1|Text=LED2|IsCrossSheetConnector=T
|RECORD=17|IndexInSheet=34|OwnerPartId=-1|ShowNetName=T|Location.X=890|Location.Y=770|Orientation=2|Color=255|FontID=1|Text=LED3|IsCrossSheetConnector=T
|RECORD=17|IndexInSheet=35|OwnerPartId=-1|ShowNetName=T|Location.X=990|Location.Y=770|Orientation=2|Color=255|FontID=1|Text=LED4|IsCrossSheetConnector=T
|RECORD=4|IndexInSheet=36|OwnerPartId=-1|Location.X=750|Location.Y=950|Color=8388608|FontID=5|Text=SYSTEM STATUS LEDS
|RECORD=1|LibReference=RES|ComponentDescription=ERJ-3EKF2000V|PartCount=2|DisplayModeCount=2|IndexInSheet=37|OwnerPartId=-1|Location.X=690|Location.Y=800|Orientation=1|CurrentPartId=1|SourceLibraryName=Altium Content Vault|TargetFileName=*|AreaColor=11599871|Color=128|PartIDLocked=F|DesignItemId=CMP-2000-00316-1|AllPinCount=2
|RECORD=2|OwnerIndex=53|OwnerPartId=1|OwnerPartDisplayMode=1|FormalType=1|Electrical=4|PinConglomerate=33|PinLength=10|Location.X=700|Location.Y=820|Name=2|Designator=2|PinPropagationDelay=0.000000E+000
|RECORD=2|OwnerIndex=53|OwnerPartId=1|OwnerPartDisplayMode=1|FormalType=1|Electrical=4|PinConglomerate=35|PinLength=10|Location.X=700|Location.Y=800|Name=1|Designator=1|PinPropagationDelay=0.000000E+000
|RECORD=14|OwnerIndex=53|IsNotAccesible=T|IndexInSheet=2|OwnerPartId=1|OwnerPartDisplayMode=1|Location.X=696|Location.Y=800|Corner.X=704|Corner.Y=820|LineWidth=1|Color=16711680|AreaColor=11599871
|RECORD=2|OwnerIndex=53|OwnerPartId=1|FormalType=1|Electrical=4|PinConglomerate=33|PinLength=10|Location.X=700|Location.Y=820|Name=2|Designator=2|PinPropagationDelay=0.000000E+000
|RECORD=2|OwnerIndex=53|OwnerPartId=1|FormalType=1|Electrical=4|PinConglomerate=35|PinLength=10|Location.X=700|Location.Y=800|Name=1|Designator=1|PinPropagationDelay=0.000000E+000
|RECORD=6|OwnerIndex=53|IsNotAccesible=T|IndexInSheet=5|OwnerPartId=1|LineWidth=1|Color=16711680|LocationCount=10|X1=700|Y1=820|X2=700|Y2=816|X3=702|Y3=815|X4=698|Y4=813|X5=702|Y5=811|X6=698|Y6=809|X7=702|Y7=807|X8=698|Y8=805|X9=700|Y9=804|X10=700|Y10=800
|RECORD=41|OwnerIndex=53|IndexInSheet=6|OwnerPartId=-1|Location.X=697|Location.Y=832|Color=8388608|FontID=1|IsHidden=T|Text=Panasonic|Name=Manufacturer
|RECORD=41|OwnerIndex=53|IndexInSheet=7|OwnerPartId=-1|Location.X=697|Location.Y=832|Color=8388608|FontID=1|IsHidden=T|Text=ERJ-3EKF2000V|Name=Part Number
|RECORD=34|OwnerIndex=53|IndexInSheet=-1|OwnerPartId=-1|Location.X=703|Location.Y=811|Color=8388608|FontID=1|Text=R35|Name=Designator|ReadOnlyState=1
|RECORD=41|OwnerIndex=53|IndexInSheet=-1|OwnerPartId=-1|Location.X=703|Location.Y=801|Color=8388608|FontID=1|Text=200 OHM|Name=Comment
|RECORD=44|OwnerIndex=53
|RECORD=45|OwnerIndex=68|IndexInSheet=-1|Description=Chip Resistor, 2-Leads, Body 1.60x0.80mm, IPC Medium Density|UseComponentLibrary=T|ModelName=RESC1608X55X30NL15T15|ModelType=PCBLIB|DatafileCount=1|ModelDatafileEntity0=RESC1608X55X30NL15T15|ModelDatafileKind0=PCBLib|IsCurrent=T|DatalinksLocked=T|DatabaseDatalinksLocked=T
|RECORD=46|OwnerIndex=69
|RECORD=48|OwnerIndex=69
|RECORD=41|OwnerIndex=71|IndexInSheet=-1|OwnerPartId=-1|Color=8388608|FontID=1|Text=2D|Name=Available Preview Images
|RECORD=45|OwnerIndex=68|IndexInSheet=-1|Description=Chip Resistor, 2-Leads, Body 1.60x0.80mm, IPC Low Density|UseComponentLibrary=T|ModelName=RESC1608X55X30ML15T15|ModelType=PCBLIB|DatafileCount=1|ModelDatafileEntity0=RESC1608X55X30ML15T15|ModelDatafileKind0=PCBLib|DatalinksLocked=T|DatabaseDatalinksLocked=T
|RECORD=46|OwnerIndex=73
|RECORD=48|OwnerIndex=73
|RECORD=41|OwnerIndex=75|IndexInSheet=-1|OwnerPartId=-1|Color=8388608|FontID=1|Text=2D|Name=Available Preview Images
|RECORD=45|OwnerIndex=68|IndexInSheet=-1|Description=Chip Resistor, 2-Leads, Body 1.60x0.80mm, IPC High Density|UseComponentLibrary=T|ModelName=RESC1608X55X30LL15T15|ModelType=PCBLIB|DatafileCount=1|ModelDatafileEntity0=RESC1608X55X30LL15T15|ModelDatafileKind0=PCBLib|DatalinksLocked=T|DatabaseDatalinksLocked=T
|RECORD=46|OwnerIndex=77
|RECORD=48|OwnerIndex=77
|RECORD=41|OwnerIndex=79|IndexInSheet=-1|OwnerPartId=-1|Color=8388608|FontID=1|Text=2D|Name=Available Preview Images
|RECORD=1|LibReference=RES|ComponentDescription=ERJ-3EKF2000V|PartCount=2|DisplayModeCount=2|IndexInSheet=38|OwnerPartId=-1|Location.X=790|Location.Y=800|Orientation=1|CurrentPartId=1|SourceLibraryName=Altium Content Vault|TargetFileName=*|AreaColor=11599871|Color=128|PartIDLocked=F|DesignItemId=CMP-2000-00316-1|AllPinCount=2
|RECORD=2|OwnerIndex=81|OwnerPartId=1|OwnerPartDisplayMode=1|FormalType=1|Electrical=4|PinConglomerate=33|PinLength=10|Location.X=800|Location.Y=820|Name=2|Designator=2|PinPropagationDelay=0.000000E+000
|RECORD=2|OwnerIndex=81|OwnerPartId=1|OwnerPartDisplayMode=1|FormalType=1|Electrical=4|PinConglomerate=35|PinLength=10|Location.X=800|Location.Y=800|Name=1|Designator=1|PinPropagationDelay=0.000000E+000
|RECORD=14|OwnerIndex=81|IsNotAccesible=T|IndexInSheet=2|OwnerPartId=1|OwnerPartDisplayMode=1|Location.X=796|Location.Y=800|Corner.X=804|Corner.Y=820|LineWidth=1|Color=16711680|AreaColor=11599871
|RECORD=2|OwnerIndex=81|OwnerPartId=1|FormalType=1|Electrical=4|PinConglomerate=33|PinLength=10|Location.X=800|Location.Y=820|Name=2|Designator=2|PinPropagationDelay=0.000000E+000
|RECORD=2|OwnerIndex=81|OwnerPartId=1|FormalType=1|Electrical=4|PinConglomerate=35|PinLength=10|Location.X=800|Location.Y=800|Name=1|Designator=1|PinPropagationDelay=0.000000E+000
|RECORD=6|OwnerIndex=81|IsNotAccesible=T|IndexInSheet=5|OwnerPartId=1|LineWidth=1|Color=16711680|LocationCount=10|X1=800|Y1=820|X2=800|Y2=816|X3=802|Y3=815|X4=798|Y4=813|X5=802|Y5=811|X6=798|Y6=809|X7=802|Y7=807|X8=798|Y8=805|X9=800|Y9=804|X10=800|Y10=800
|RECORD=41|OwnerIndex=81|IndexInSheet=6|OwnerPartId=-1|Location.X=797|Location.Y=832|Color=8388608|FontID=1|IsHidden=T|Text=Panasonic|Name=Manufacturer
|RECORD=41|OwnerIndex=81|IndexInSheet=7|OwnerPartId=-1|Location.X=797|Location.Y=832|Color=8388608|FontID=1|IsHidden=T|Text=ERJ-3EKF2000V|Name=Part Number
|RECORD=34|OwnerIndex=81|IndexInSheet=-1|OwnerPartId=-1|Location.X=803|Location.Y=811|Color=8388608|FontID=1|Text=R36|Name=Designator|ReadOnlyState=1
|RECORD=41|OwnerIndex=81|IndexInSheet=-1|OwnerPartId=-1|Location.X=803|Location.Y=801|Color=8388608|FontID=1|Text=200 OHM|Name=Comment
|RECORD=44|OwnerIndex=81
|RECORD=45|OwnerIndex=96|IndexInSheet=-1|Description=Chip Resistor, 2-Leads, Body 1.60x0.80mm, IPC Medium Density|UseComponentLibrary=T|ModelName=RESC1608X55X30NL15T15|ModelType=PCBLIB|DatafileCount=1|ModelDatafileEntity0=RESC1608X55X30NL15T15|ModelDatafileKind0=PCBLib|IsCurrent=T|DatalinksLocked=T|DatabaseDatalinksLocked=T
|RECORD=46|OwnerIndex=97
|RECORD=48|OwnerIndex=97
|RECORD=41|OwnerIndex=99|IndexInSheet=-1|OwnerPartId=-1|Color=8388608|FontID=1|Text=2D|Name=Available Preview Images
|RECORD=45|OwnerIndex=96|IndexInSheet=-1|Description=Chip Resistor, 2-Leads, Body 1.60x0.80mm, IPC Low Density|UseComponentLibrary=T|ModelName=RESC1608X55X30ML15T15|ModelType=PCBLIB|DatafileCount=1|ModelDatafileEntity0=RESC1608X55X30ML15T15|ModelDatafileKind0=PCBLib|DatalinksLocked=T|DatabaseDatalinksLocked=T
|RECORD=46|OwnerIndex=101
|RECORD=48|OwnerIndex=101
|RECORD=41|OwnerIndex=103|IndexInSheet=-1|OwnerPartId=-1|Color=8388608|FontID=1|Text=2D|Name=Available Preview Images
|RECORD=45|OwnerIndex=96|IndexInSheet=-1|Description=Chip Resistor, 2-Leads, Body 1.60x0.80mm, IPC High Density|UseComponentLibrary=T|ModelName=RESC1608X55X30LL15T15|ModelType=PCBLIB|DatafileCount=1|ModelDatafileEntity0=RESC1608X55X30LL15T15|ModelDatafileKind0=PCBLib|DatalinksLocked=T|DatabaseDatalinksLocked=T
|RECORD=46|OwnerIndex=105
|RECORD=48|OwnerIndex=105
|RECORD=41|OwnerIndex=107|IndexInSheet=-1|OwnerPartId=-1|Color=8388608|FontID=1|Text=2D|Name=Available Preview Images
|RECORD=1|LibReference=RES|ComponentDescription=ERJ-3EKF2000V|PartCount=2|DisplayModeCount=2|IndexInSheet=39|OwnerPartId=-1|Location.X=890|Location.Y=800|Orientation=1|CurrentPartId=1|SourceLibraryName=Altium Content Vault|TargetFileName=*|AreaColor=11599871|Color=128|PartIDLocked=F|DesignItemId=CMP-2000-00316-1|AllPinCount=2
|RECORD=2|OwnerIndex=109|OwnerPartId=1|OwnerPartDisplayMode=1|FormalType=1|Electrical=4|PinConglomerate=33|PinLength=10|Location.X=900|Location.Y=820|Name=2|Designator=2|PinPropagationDelay=0.000000E+000
|RECORD=2|OwnerIndex=109|OwnerPartId=1|OwnerPartDisplayMode=1|FormalType=1|Electrical=4|PinConglomerate=35|PinLength=10|Location.X=900|Location.Y=800|Name=1|Designator=1|PinPropagationDelay=0.000000E+000
|RECORD=14|OwnerIndex=109|IsNotAccesible=T|IndexInSheet=2|OwnerPartId=1|OwnerPartDisplayMode=1|Location.X=896|Location.Y=800|Corner.X=904|Corner.Y=820|LineWidth=1|Color=16711680|AreaColor=11599871
|RECORD=2|OwnerIndex=109|OwnerPartId=1|FormalType=1|Electrical=4|PinConglomerate=33|PinLength=10|Location.X=900|Location.Y=820|Name=2|Designator=2|PinPropagationDelay=0.000000E+000
|RECORD=2|OwnerIndex=109|OwnerPartId=1|FormalType=1|Electrical=4|PinConglomerate=35|PinLength=10|Location.X=900|Location.Y=800|Name=1|Designator=1|PinPropagationDelay=0.000000E+000
|RECORD=6|OwnerIndex=109|IsNotAccesible=T|IndexInSheet=5|OwnerPartId=1|LineWidth=1|Color=16711680|LocationCount=10|X1=900|Y1=820|X2=900|Y2=816|X3=902|Y3=815|X4=898|Y4=813|X5=902|Y5=811|X6=898|Y6=809|X7=902|Y7=807|X8=898|Y8=805|X9=900|Y9=804|X10=900|Y10=800
|RECORD=41|OwnerIndex=109|IndexInSheet=6|OwnerPartId=-1|Location.X=897|Location.Y=832|Color=8388608|FontID=1|IsHidden=T|Text=Panasonic|Name=Manufacturer
|RECORD=41|OwnerIndex=109|IndexInSheet=7|OwnerPartId=-1|Location.X=897|Location.Y=832|Color=8388608|FontID=1|IsHidden=T|Text=ERJ-3EKF2000V|Name=Part Number
|RECORD=34|OwnerIndex=109|IndexInSheet=-1|OwnerPartId=-1|Location.X=903|Location.Y=811|Color=8388608|FontID=1|Text=R38|Name=Designator|ReadOnlyState=1
|RECORD=41|OwnerIndex=109|IndexInSheet=-1|OwnerPartId=-1|Location.X=903|Location.Y=801|Color=8388608|FontID=1|Text=200 OHM|Name=Comment
|RECORD=44|OwnerIndex=109
|RECORD=45|OwnerIndex=124|IndexInSheet=-1|Description=Chip Resistor, 2-Leads, Body 1.60x0.80mm, IPC Medium Density|UseComponentLibrary=T|ModelName=RESC1608X55X30NL15T15|ModelType=PCBLIB|DatafileCount=1|ModelDatafileEntity0=RESC1608X55X30NL15T15|ModelDatafileKind0=PCBLib|IsCurrent=T|DatalinksLocked=T|DatabaseDatalinksLocked=T
|RECORD=46|OwnerIndex=125
|RECORD=48|OwnerIndex=125
|RECORD=41|OwnerIndex=127|IndexInSheet=-1|OwnerPartId=-1|Color=8388608|FontID=1|Text=2D|Name=Available Preview Images
|RECORD=45|OwnerIndex=124|IndexInSheet=-1|Description=Chip Resistor, 2-Leads, Body 1.60x0.80mm, IPC Low Density|UseComponentLibrary=T|ModelName=RESC1608X55X30ML15T15|ModelType=PCBLIB|DatafileCount=1|ModelDatafileEntity0=RESC1608X55X30ML15T15|ModelDatafileKind0=PCBLib|DatalinksLocked=T|DatabaseDatalinksLocked=T
|RECORD=46|OwnerIndex=129
|RECORD=48|OwnerIndex=129
|RECORD=41|OwnerIndex=131|IndexInSheet=-1|OwnerPartId=-1|Color=8388608|FontID=1|Text=2D|Name=Available Preview Images
|RECORD=45|OwnerIndex=124|IndexInSheet=-1|Description=Chip Resistor, 2-Leads, Body 1.60x0.80mm, IPC High Density|UseComponentLibrary=T|ModelName=RESC1608X55X30LL15T15|ModelType=PCBLIB|DatafileCount=1|ModelDatafileEntity0=RESC1608X55X30LL15T15|ModelDatafileKind0=PCBLib|DatalinksLocked=T|DatabaseDatalinksLocked=T
|RECORD=46|OwnerIndex=133
|RECORD=48|OwnerIndex=133
|RECORD=41|OwnerIndex=135|IndexInSheet=-1|OwnerPartId=-1|Color=8388608|FontID=1|Text=2D|Name=Available Preview Images
|RECORD=1|LibReference=RES|ComponentDescription=ERJ-3EKF2000V|PartCount=2|DisplayModeCount=2|IndexInSheet=40|OwnerPartId=-1|Location.X=990|Location.Y=800|Orientation=1|CurrentPartId=1|SourceLibraryName=Altium Content Vault|TargetFileName=*|AreaColor=11599871|Color=128|PartIDLocked=F|DesignItemId=CMP-2000-00316-1|AllPinCount=2
|RECORD=2|OwnerIndex=137|OwnerPartId=1|OwnerPartDisplayMode=1|FormalType=1|Electrical=4|PinConglomerate=33|PinLength=10|Location.X=1000|Location.Y=820|Name=2|Designator=2|PinPropagationDelay=0.000000E+000
|RECORD=2|OwnerIndex=137|OwnerPartId=1|OwnerPartDisplayMode=1|FormalType=1|Electrical=4|PinConglomerate=35|PinLength=10|Location.X=1000|Location.Y=800|Name=1|Designator=1|PinPropagationDelay=0.000000E+000
|RECORD=14|OwnerIndex=137|IsNotAccesible=T|IndexInSheet=2|OwnerPartId=1|OwnerPartDisplayMode=1|Location.X=996|Location.Y=800|Corner.X=1004|Corner.Y=820|LineWidth=1|Color=16711680|AreaColor=11599871
|RECORD=2|OwnerIndex=137|OwnerPartId=1|FormalType=1|Electrical=4|PinConglomerate=33|PinLength=10|Location.X=1000|Location.Y=820|Name=2|Designator=2|PinPropagationDelay=0.000000E+000
|RECORD=2|OwnerIndex=137|OwnerPartId=1|FormalType=1|Electrical=4|PinConglomerate=35|PinLength=10|Location.X=1000|Location.Y=800|Name=1|Designator=1|PinPropagationDelay=0.000000E+000
|RECORD=6|OwnerIndex=137|IsNotAccesible=T|IndexInSheet=5|OwnerPartId=1|LineWidth=1|Color=16711680|LocationCount=10|X1=1000|Y1=820|X2=1000|Y2=816|X3=1002|Y3=815|X4=998|Y4=813|X5=1002|Y5=811|X6=998|Y6=809|X7=1002|Y7=807|X8=998|Y8=805|X9=1000|Y9=804|X10=1000|Y10=800
|RECORD=41|OwnerIndex=137|IndexInSheet=6|OwnerPartId=-1|Location.X=997|Location.Y=832|Color=8388608|FontID=1|IsHidden=T|Text=Panasonic|Name=Manufacturer
|RECORD=41|OwnerIndex=137|IndexInSheet=7|OwnerPartId=-1|Location.X=997|Location.Y=832|Color=8388608|FontID=1|IsHidden=T|Text=ERJ-3EKF2000V|Name=Part Number
|RECORD=34|OwnerIndex=137|IndexInSheet=-1|OwnerPartId=-1|Location.X=1003|Location.Y=811|Color=8388608|FontID=1|Text=R39|Name=Designator|ReadOnlyState=1
|RECORD=41|OwnerIndex=137|IndexInSheet=-1|OwnerPartId=-1|Location.X=1003|Location.Y=801|Color=8388608|FontID=1|Text=200 OHM|Name=Comment
|RECORD=44|OwnerIndex=137
|RECORD=45|OwnerIndex=152|IndexInSheet=-1|Description=Chip Resistor, 2-Leads, Body 1.60x0.80mm, IPC Medium Density|UseComponentLibrary=T|ModelName=RESC1608X55X30NL15T15|ModelType=PCBLIB|DatafileCount=1|ModelDatafileEntity0=RESC1608X55X30NL15T15|ModelDatafileKind0=PCBLib|IsCurrent=T|DatalinksLocked=T|DatabaseDatalinksLocked=T
|RECORD=46|OwnerIndex=153
|RECORD=48|OwnerIndex=153
|RECORD=41|OwnerIndex=155|IndexInSheet=-1|OwnerPartId=-1|Color=8388608|FontID=1|Text=2D|Name=Available Preview Images
|RECORD=45|OwnerIndex=152|IndexInSheet=-1|Description=Chip Resistor, 2-Leads, Body 1.60x0.80mm, IPC Low Density|UseComponentLibrary=T|ModelName=RESC1608X55X30ML15T15|ModelType=PCBLIB|DatafileCount=1|ModelDatafileEntity0=RESC1608X55X30ML15T15|ModelDatafileKind0=PCBLib|DatalinksLocked=T|DatabaseDatalinksLocked=T
|RECORD=46|OwnerIndex=157
|RECORD=48|OwnerIndex=157
|RECORD=41|OwnerIndex=159|IndexInSheet=-1|OwnerPartId=-1|Color=8388608|FontID=1|Text=2D|Name=Available Preview Images
|RECORD=45|OwnerIndex=152|IndexInSheet=-1|Description=Chip Resistor, 2-Leads, Body 1.60x0.80mm, IPC High Density|UseComponentLibrary=T|ModelName=RESC1608X55X30LL15T15|ModelType=PCBLIB|DatafileCount=1|ModelDatafileEntity0=RESC1608X55X30LL15T15|ModelDatafileKind0=PCBLib|DatalinksLocked=T|DatabaseDatalinksLocked=T
|RECORD=46|OwnerIndex=161
|RECORD=48|OwnerIndex=161
|RECORD=41|OwnerIndex=163|IndexInSheet=-1|OwnerPartId=-1|Color=8388608|FontID=1|Text=2D|Name=Available Preview Images
|RECORD=1|LibReference=155124M173200|ComponentDescription=LED (Multiple)|PartCount=2|DisplayModeCount=1|IndexInSheet=41|OwnerPartId=-1|Location.X=1230|Location.Y=560|IsMirrored=T|CurrentPartId=1|LibraryPath=*|SourceLibraryName=SamacSys.SchLib|TargetFileName=*|AreaColor=11599871|Color=128|PartIDLocked=T|DesignItemId=155124M173200|AllPinCount=4
|RECORD=41|OwnerIndex=165|OwnerPartId=-1|Location.X=1148|Location.Y=560|Color=8388608|FontID=6|IsHidden=T|Text=https://www.mouser.com/ds/2/445/155124M173200-1113601.pdf|Name=Datasheet Link|IsMirrored=T
|RECORD=41|OwnerIndex=165|IndexInSheet=1|OwnerPartId=-1|Location.X=1148|Location.Y=560|Color=8388608|FontID=1|IsHidden=T|Text=Wurth Elektronik|Name=Manufacturer_Name|IsMirrored=T
|RECORD=41|OwnerIndex=165|IndexInSheet=2|OwnerPartId=-1|Location.X=1148|Location.Y=560|Color=8388608|FontID=1|IsHidden=T|Text=155124M173200|Name=Manufacturer_Part_Number|IsMirrored=T
|RECORD=41|OwnerIndex=165|IndexInSheet=3|OwnerPartId=-1|Location.X=1148|Location.Y=560|Color=8388608|FontID=1|IsHidden=T|Text=710-155124M173200|Name=Mouser Part Number|IsMirrored=T
|RECORD=41|OwnerIndex=165|IndexInSheet=4|OwnerPartId=-1|Location.X=1148|Location.Y=560|Color=8388608|FontID=6|IsHidden=T|Text=https://www.mouser.co.uk/ProductDetail/Wurth-Elektronik/155124M173200?qs=5aG0NVq1C4xPhoUU07x4gQ%3D%3D|Name=Mouser Price/Stock|IsMirrored=T
|RECORD=41|OwnerIndex=165|IndexInSheet=5|OwnerPartId=-1|Location.X=1148|Location.Y=560|Color=8388608|FontID=1|IsHidden=T|Name=Arrow Part Number|IsMirrored=T
|RECORD=41|OwnerIndex=165|IndexInSheet=6|OwnerPartId=-1|Location.X=1148|Location.Y=560|Color=8388608|FontID=1|IsHidden=T|Name=Arrow Price/Stock|IsMirrored=T
|RECORD=14|OwnerIndex=165|IsNotAccesible=T|IndexInSheet=7|OwnerPartId=1|Location.X=1170|Location.Y=520|Corner.X=1230|Corner.Y=560|LineWidth=1|Color=128|AreaColor=11599871|IsSolid=T
|RECORD=2|OwnerIndex=165|OwnerPartId=1|FormalType=1|Electrical=7|PinConglomerate=56|PinLength=20|Location.X=1230|Location.Y=550|Name=ANODE|Designator=1|SwapIDPart=Ž&Ž||PinPropagationDelay=0.000000E+000
|RECORD=2|OwnerIndex=165|OwnerPartId=1|FormalType=1|Electrical=2|PinConglomerate=58|PinLength=20|Location.X=1170|Location.Y=530|Name=B|Designator=2|SwapIDPart=Ž&Ž||PinPropagationDelay=0.000000E+000
|RECORD=2|OwnerIndex=165|OwnerPartId=1|FormalType=1|Electrical=2|PinConglomerate=58|PinLength=20|Location.X=1170|Location.Y=540|Name=G|Designator=3|SwapIDPart=Ž&Ž||PinPropagationDelay=0.000000E+000
|RECORD=2|OwnerIndex=165|OwnerPartId=1|FormalType=1|Electrical=2|PinConglomerate=58|PinLength=20|Location.X=1170|Location.Y=550|Name=R|Designator=4|SwapIDPart=Ž&Ž||PinPropagationDelay=0.000000E+000
|RECORD=34|OwnerIndex=165|IndexInSheet=-1|OwnerPartId=-1|Location.X=1170|Location.Y=560|Color=8388608|FontID=1|Text=D13|Name=Designator|ReadOnlyState=1|IsMirrored=T
|RECORD=41|OwnerIndex=165|IndexInSheet=-1|OwnerPartId=-1|Location.X=1170|Location.Y=510|Color=8388608|FontID=1|Text=155124M173200|Name=Comment|IsMirrored=T
|RECORD=44|OwnerIndex=165
|RECORD=45|OwnerIndex=184|IndexInSheet=-1|ModelName=155124M173200|ModelType=PCBLIB|DatafileCount=1|ModelDatafile0=C:\Users\<user>\Documents\AltiumLL\SamacSys.PcbLib|ModelDatafileEntity0=155124M173200|ModelDatafileKind0=PCBLIB|IsCurrent=T
|RECORD=46|OwnerIndex=185
|RECORD=48|OwnerIndex=185
|RECORD=1|LibReference=155124M173200|ComponentDescription=LED (Multiple)|PartCount=2|DisplayModeCount=1|IndexInSheet=42|OwnerPartId=-1|Location.X=1230|Location.Y=500|IsMirrored=T|CurrentPartId=1|LibraryPath=*|SourceLibraryName=SamacSys.SchLib|TargetFileName=*|AreaColor=11599871|Color=128|PartIDLocked=T|DesignItemId=155124M173200|AllPinCount=4
|RECORD=41|OwnerIndex=188|OwnerPartId=-1|Location.X=1148|Location.Y=500|Color=8388608|FontID=6|IsHidden=T|Text=https://www.mouser.com/ds/2/445/155124M173200-1113601.pdf|Name=Datasheet Link|IsMirrored=T
|RECORD=41|OwnerIndex=188|IndexInSheet=1|OwnerPartId=-1|Location.X=1148|Location.Y=500|Color=8388608|FontID=1|IsHidden=T|Text=Wurth Elektronik|Name=Manufacturer_Name|IsMirrored=T
|RECORD=41|OwnerIndex=188|IndexInSheet=2|OwnerPartId=-1|Location.X=1148|Location.Y=500|Color=8388608|FontID=1|IsHidden=T|Text=155124M173200|Name=Manufacturer_Part_Number|IsMirrored=T
|RECORD=41|OwnerIndex=188|IndexInSheet=3|OwnerPartId=-1|Location.X=1148|Location.Y=500|Color=8388608|FontID=1|IsHidden=T|Text=710-155124M173200|Name=Mouser Part Number|IsMirrored=T
|RECORD=41|OwnerIndex=188|IndexInSheet=4|OwnerPartId=-1|Location.X=1148|Location.Y=500|Color=8388608|FontID=6|IsHidden=T|Text=https://www.mouser.co.uk/ProductDetail/Wurth-Elektronik/155124M173200?qs=5aG0NVq1C4xPhoUU07x4gQ%3D%3D|Name=Mouser Price/Stock|IsMirrored=T
|RECORD=41|OwnerIndex=188|IndexInSheet=5|OwnerPartId=-1|Location.X=1148|Location.Y=500|Color=8388608|FontID=1|IsHidden=T|Name=Arrow Part Number|IsMirrored=T
|RECORD=41|OwnerIndex=188|IndexInSheet=6|OwnerPartId=-1|Location.X=1148|Location.Y=500|Color=8388608|FontID=1|IsHidden=T|Name=Arrow Price/Stock|IsMirrored=T
|RECORD=14|OwnerIndex=188|IsNotAccesible=T|IndexInSheet=7|OwnerPartId=1|Location.X=1170|Location.Y=460|Corner.X=1230|Corner.Y=500|LineWidth=1|Color=128|AreaColor=11599871|IsSolid=T
|RECORD=2|OwnerIndex=188|OwnerPartId=1|FormalType=1|Electrical=7|PinConglomerate=56|PinLength=20|Location.X=1230|Location.Y=490|Name=ANODE|Designator=1|SwapIDPart=Ž&Ž||PinPropagationDelay=0.000000E+000
|RECORD=2|OwnerIndex=188|OwnerPartId=1|FormalType=1|Electrical=2|PinConglomerate=58|PinLength=20|Location.X=1170|Location.Y=470|Name=B|Designator=2|SwapIDPart=Ž&Ž||PinPropagationDelay=0.000000E+000
|RECORD=2|OwnerIndex=188|OwnerPartId=1|FormalType=1|Electrical=2|PinConglomerate=58|PinLength=20|Location.X=1170|Location.Y=480|Name=G|Designator=3|SwapIDPart=Ž&Ž||PinPropagationDelay=0.000000E+000
|RECORD=2|OwnerIndex=188|OwnerPartId=1|FormalType=1|Electrical=2|PinConglomerate=58|PinLength=20|Location.X=1170|Location.Y=490|Name=R|Designator=4|SwapIDPart=Ž&Ž||PinPropagationDelay=0.000000E+000
|RECORD=34|OwnerIndex=188|IndexInSheet=-1|OwnerPartId=-1|Location.X=1170|Location.Y=500|Color=8388608|FontID=1|Text=D14|Name=Designator|ReadOnlyState=1|IsMirrored=T
|RECORD=41|OwnerIndex=188|IndexInSheet=-1|OwnerPartId=-1|Location.X=1170|Location.Y=450|Color=8388608|FontID=1|Text=155124M173200|Name=Comment|IsMirrored=T
|RECORD=44|OwnerIndex=188
|RECORD=45|OwnerIndex=207|IndexInSheet=-1|ModelName=155124M173200|ModelType=PCBLIB|DatafileCount=1|ModelDatafile0=C:\Users\<user>\Documents\AltiumLL\SamacSys.PcbLib|ModelDatafileEntity0=155124M173200|ModelDatafileKind0=PCBLIB|IsCurrent=T
|RECORD=46|OwnerIndex=208
|RECORD=48|OwnerIndex=208
|RECORD=1|LibReference=155124M173200|ComponentDescription=LED (Multiple)|PartCount=2|DisplayModeCount=1|IndexInSheet=43|OwnerPartId=-1|Location.X=1230|Location.Y=440|IsMirrored=T|CurrentPartId=1|LibraryPath=*|SourceLibraryName=SamacSys.SchLib|TargetFileName=*|AreaColor=11599871|Color=128|PartIDLocked=T|DesignItemId=155124M173200|AllPinCount=4
|RECORD=41|OwnerIndex=211|OwnerPartId=-1|Location.X=1148|Location.Y=440|Color=8388608|FontID=6|IsHidden=T|Text=https://www.mouser.com/ds/2/445/155124M173200-1113601.pdf|Name=Datasheet Link|IsMirrored=T
|RECORD=41|OwnerIndex=211|IndexInSheet=1|OwnerPartId=-1|Location.X=1148|Location.Y=440|Color=8388608|FontID=1|IsHidden=T|Text=Wurth Elektronik|Name=Manufacturer_Name|IsMirrored=T
|RECORD=41|OwnerIndex=211|IndexInSheet=2|OwnerPartId=-1|Location.X=1148|Location.Y=440|Color=8388608|FontID=1|IsHidden=T|Text=155124M173200|Name=Manufacturer_Part_Number|IsMirrored=T
|RECORD=41|OwnerIndex=211|IndexInSheet=3|OwnerPartId=-1|Location.X=1148|Location.Y=440|Color=8388608|FontID=1|IsHidden=T|Text=710-155124M173200|Name=Mouser Part Number|IsMirrored=T
|RECORD=41|OwnerIndex=211|IndexInSheet=4|OwnerPartId=-1|Location.X=1148|Location.Y=440|Color=8388608|FontID=6|IsHidden=T|Text=https://www.mouser.co.uk/ProductDetail/Wurth-Elektronik/155124M173200?qs=5aG0NVq1C4xPhoUU07x4gQ%3D%3D|Name=Mouser Price/Stock|IsMirrored=T
|RECORD=41|OwnerIndex=211|IndexInSheet=5|OwnerPartId=-1|Location.X=1148|Location.Y=440|Color=8388608|FontID=1|IsHidden=T|Name=Arrow Part Number|IsMirrored=T
|RECORD=41|OwnerIndex=211|IndexInSheet=6|OwnerPartId=-1|Location.X=1148|Location.Y=440|Color=8388608|FontID=1|IsHidden=T|Name=Arrow Price/Stock|IsMirrored=T
|RECORD=14|OwnerIndex=211|IsNotAccesible=T|IndexInSheet=7|OwnerPartId=1|Location.X=1170|Location.Y=400|Corner.X=1230|Corner.Y=440|LineWidth=1|Color=128|AreaColor=11599871|IsSolid=T
|RECORD=2|OwnerIndex=211|OwnerPartId=1|FormalType=1|Electrical=7|PinConglomerate=56|PinLength=20|Location.X=1230|Location.Y=430|Name=ANODE|Designator=1|SwapIDPart=Ž&Ž||PinPropagationDelay=0.000000E+000
|RECORD=2|OwnerIndex=211|OwnerPartId=1|FormalType=1|Electrical=2|PinConglomerate=58|PinLength=20|Location.X=1170|Location.Y=410|Name=B|Designator=2|SwapIDPart=Ž&Ž||PinPropagationDelay=0.000000E+000
|RECORD=2|OwnerIndex=211|OwnerPartId=1|FormalType=1|Electrical=2|PinConglomerate=58|PinLength=20|Location.X=1170|Location.Y=420|Name=G|Designator=3|SwapIDPart=Ž&Ž||PinPropagationDelay=0.000000E+000
|RECORD=2|OwnerIndex=211|OwnerPartId=1|FormalType=1|Electrical=2|PinConglomerate=58|PinLength=20|Location.X=1170|Location.Y=430|Name=R|Designator=4|SwapIDPart=Ž&Ž||PinPropagationDelay=0.000000E+000
|RECORD=34|OwnerIndex=211|IndexInSheet=-1|OwnerPartId=-1|Location.X=1170|Location.Y=440|Color=8388608|FontID=1|Text=D15|Name=Designator|ReadOnlyState=1|IsMirrored=T
|RECORD=41|OwnerIndex=211|IndexInSheet=-1|OwnerPartId=-1|Location.X=1170|Location.Y=390|Color=8388608|FontID=1|Text=155124M173200|Name=Comment|IsMirrored=T
|RECORD=44|OwnerIndex=211
|RECORD=45|OwnerIndex=230|IndexInSheet=-1|ModelName=155124M173200|ModelType=PCBLIB|DatafileCount=1|ModelDatafile0=C:\Users\<user>\Documents\AltiumLL\SamacSys.PcbLib|ModelDatafileEntity0=155124M173200|ModelDatafileKind0=PCBLIB|IsCurrent=T
|RECORD=46|OwnerIndex=231
|RECORD=48|OwnerIndex=231
|RECORD=1|LibReference=155124M173200|ComponentDescription=LED (Multiple)|PartCount=2|DisplayModeCount=1|IndexInSheet=44|OwnerPartId=-1|Location.X=1230|Location.Y=380|IsMirrored=T|CurrentPartId=1|LibraryPath=*|SourceLibraryName=SamacSys.SchLib|TargetFileName=*|AreaColor=11599871|Color=128|PartIDLocked=T|DesignItemId=155124M173200|AllPinCount=4
|RECORD=41|OwnerIndex=234|OwnerPartId=-1|Location.X=1148|Location.Y=380|Color=8388608|FontID=6|IsHidden=T|Text=https://www.mouser.com/ds/2/445/155124M173200-1113601.pdf|Name=Datasheet Link|IsMirrored=T
|RECORD=41|OwnerIndex=234|IndexInSheet=1|OwnerPartId=-1|Location.X=1148|Location.Y=380|Color=8388608|FontID=1|IsHidden=T|Text=Wurth Elektronik|Name=Manufacturer_Name|IsMirrored=T
|RECORD=41|OwnerIndex=234|IndexInSheet=2|OwnerPartId=-1|Location.X=1148|Location.Y=380|Color=8388608|FontID=1|IsHidden=T|Text=155124M173200|Name=Manufacturer_Part_Number|IsMirrored=T
|RECORD=41|OwnerIndex=234|IndexInSheet=3|OwnerPartId=-1|Location.X=1148|Location.Y=380|Color=8388608|FontID=1|IsHidden=T|Text=710-155124M173200|Name=Mouser Part Number|IsMirrored=T
|RECORD=41|OwnerIndex=234|IndexInSheet=4|OwnerPartId=-1|Location.X=1148|Location.Y=380|Color=8388608|FontID=6|IsHidden=T|Text=https://www.mouser.co.uk/ProductDetail/Wurth-Elektronik/155124M173200?qs=5aG0NVq1C4xPhoUU07x4gQ%3D%3D|Name=Mouser Price/Stock|IsMirrored=T
|RECORD=41|OwnerIndex=234|IndexInSheet=5|OwnerPartId=-1|Location.X=1148|Location.Y=380|Color=8388608|FontID=1|IsHidden=T|Name=Arrow Part Number|IsMirrored=T
|RECORD=41|OwnerIndex=234|IndexInSheet=6|OwnerPartId=-1|Location.X=1148|Location.Y=380|Color=8388608|FontID=1|IsHidden=T|Name=Arrow Price/Stock|IsMirrored=T
|RECORD=14|OwnerIndex=234|IsNotAccesible=T|IndexInSheet=7|OwnerPartId=1|Location.X=1170|Location.Y=340|Corner.X=1230|Corner.Y=380|LineWidth=1|Color=128|AreaColor=11599871|IsSolid=T
|RECORD=2|OwnerIndex=234|OwnerPartId=1|FormalType=1|Electrical=7|PinConglomerate=56|PinLength=20|Location.X=1230|Location.Y=370|Name=ANODE|Designator=1|SwapIDPart=Ž&Ž||PinPropagationDelay=0.000000E+000
|RECORD=2|OwnerIndex=234|OwnerPartId=1|FormalType=1|Electrical=2|PinConglomerate=58|PinLength=20|Location.X=1170|Location.Y=350|Name=B|Designator=2|SwapIDPart=Ž&Ž||PinPropagationDelay=0.000000E+000
|RECORD=2|OwnerIndex=234|OwnerPartId=1|FormalType=1|Electrical=2|PinConglomerate=58|PinLength=20|Location.X=1170|Location.Y=360|Name=G|Designator=3|SwapIDPart=Ž&Ž||PinPropagationDelay=0.000000E+000
|RECORD=2|OwnerIndex=234|OwnerPartId=1|FormalType=1|Electrical=2|PinConglomerate=58|PinLength=20|Location.X=1170|Location.Y=370|Name=R|Designator=4|SwapIDPart=Ž&Ž||PinPropagationDelay=0.000000E+000
|RECORD=34|OwnerIndex=234|IndexInSheet=-1|OwnerPartId=-1|Location.X=1170|Location.Y=380|Color=8388608|FontID=1|Text=D16|Name=Designator|ReadOnlyState=1|IsMirrored=T
|RECORD=41|OwnerIndex=234|IndexInSheet=-1|OwnerPartId=-1|Location.X=1170|Location.Y=330|Color=8388608|FontID=1|Text=155124M173200|Name=Comment|IsMirrored=T
|RECORD=44|OwnerIndex=234
|RECORD=45|OwnerIndex=253|IndexInSheet=-1|ModelName=155124M173200|ModelType=PCBLIB|DatafileCount=1|ModelDatafile0=C:\Users\<user>\Documents\AltiumLL\SamacSys.PcbLib|ModelDatafileEntity0=155124M173200|ModelDatafileKind0=PCBLIB|IsCurrent=T
|RECORD=46|OwnerIndex=254
|RECORD=48|OwnerIndex=254
|RECORD=1|LibReference=155124M173200|ComponentDescription=LED (Multiple)|PartCount=2|DisplayModeCount=1|IndexInSheet=45|OwnerPartId=-1|Location.X=1230|Location.Y=310|IsMirrored=T|CurrentPartId=1|LibraryPath=*|SourceLibraryName=SamacSys.SchLib|TargetFileName=*|AreaColor=11599871|Color=128|PartIDLocked=T|DesignItemId=155124M173200|AllPinCount=4
|RECORD=41|OwnerIndex=257|OwnerPartId=-1|Location.X=1148|Location.Y=310|Color=8388608|FontID=6|IsHidden=T|Text=https://www.mouser.com/ds/2/445/155124M173200-1113601.pdf|Name=Datasheet Link|IsMirrored=T
|RECORD=41|OwnerIndex=257|IndexInSheet=1|OwnerPartId=-1|Location.X=1148|Location.Y=310|Color=8388608|FontID=1|IsHidden=T|Text=Wurth Elektronik|Name=Manufacturer_Name|IsMirrored=T
|RECORD=41|OwnerIndex=257|IndexInSheet=2|OwnerPartId=-1|Location.X=1148|Location.Y=310|Color=8388608|FontID=1|IsHidden=T|Text=155124M173200|Name=Manufacturer_Part_Number|IsMirrored=T
|RECORD=41|OwnerIndex=257|IndexInSheet=3|OwnerPartId=-1|Location.X=1148|Location.Y=310|Color=8388608|FontID=1|IsHidden=T|Text=710-155124M173200|Name=Mouser Part Number|IsMirrored=T
|RECORD=41|OwnerIndex=257|IndexInSheet=4|OwnerPartId=-1|Location.X=1148|Location.Y=310|Color=8388608|FontID=6|IsHidden=T|Text=https://www.mouser.co.uk/ProductDetail/Wurth-Elektronik/155124M173200?qs=5aG0NVq1C4xPhoUU07x4gQ%3D%3D|Name=Mouser Price/Stock|IsMirrored=T
|RECORD=41|OwnerIndex=257|IndexInSheet=5|OwnerPartId=-1|Location.X=1148|Location.Y=310|Color=8388608|FontID=1|IsHidden=T|Name=Arrow Part Number|IsMirrored=T
|RECORD=41|OwnerIndex=257|IndexInSheet=6|OwnerPartId=-1|Location.X=1148|Location.Y=310|Color=8388608|FontID=1|IsHidden=T|Name=Arrow Price/Stock|IsMirrored=T
|RECORD=14|OwnerIndex=257|IsNotAccesible=T|IndexInSheet=7|OwnerPartId=1|Location.X=1170|Location.Y=270|Corner.X=1230|Corner.Y=310|LineWidth=1|Color=128|AreaColor=11599871|IsSolid=T
|RECORD=2|OwnerIndex=257|OwnerPartId=1|FormalType=1|Electrical=7|PinConglomerate=56|PinLength=20|Location.X=1230|Location.Y=300|Name=ANODE|Designator=1|SwapIDPart=Ž&Ž||PinPropagationDelay=0.000000E+000
|RECORD=2|OwnerIndex=257|OwnerPartId=1|FormalType=1|Electrical=2|PinConglomerate=58|PinLength=20|Location.X=1170|Location.Y=280|Name=B|Designator=2|SwapIDPart=Ž&Ž||PinPropagationDelay=0.000000E+000
|RECORD=2|OwnerIndex=257|OwnerPartId=1|FormalType=1|Electrical=2|PinConglomerate=58|PinLength=20|Location.X=1170|Location.Y=290|Name=G|Designator=3|SwapIDPart=Ž&Ž||PinPropagationDelay=0.000000E+000
|RECORD=2|OwnerIndex=257|OwnerPartId=1|FormalType=1|Electrical=2|PinConglomerate=58|PinLength=20|Location.X=1170|Location.Y=300|Name=R|Designator=4|SwapIDPart=Ž&Ž||PinPropagationDelay=0.000000E+000
|RECORD=34|OwnerIndex=257|IndexInSheet=-1|OwnerPartId=-1|Location.X=1170|Location.Y=310|Color=8388608|FontID=1|Text=D17|Name=Designator|ReadOnlyState=1|IsMirrored=T
|RECORD=41|OwnerIndex=257|IndexInSheet=-1|OwnerPartId=-1|Location.X=1170|Location.Y=260|Color=8388608|FontID=1|Text=155124M173200|Name=Comment|IsMirrored=T
|RECORD=44|OwnerIndex=257
|RECORD=45|OwnerIndex=276|IndexInSheet=-1|ModelName=155124M173200|ModelType=PCBLIB|DatafileCount=1|ModelDatafile0=C:\Users\<user>\Documents\AltiumLL\SamacSys.PcbLib|ModelDatafileEntity0=155124M173200|ModelDatafileKind0=PCBLIB|IsCurrent=T
|RECORD=46|OwnerIndex=277
|RECORD=48|OwnerIndex=277
|RECORD=1|LibReference=155124M173200|ComponentDescription=LED (Multiple)|PartCount=2|DisplayModeCount=1|IndexInSheet=46|OwnerPartId=-1|Location.X=1230|Location.Y=240|IsMirrored=T|CurrentPartId=1|LibraryPath=*|SourceLibraryName=SamacSys.SchLib|TargetFileName=*|AreaColor=11599871|Color=128|PartIDLocked=T|DesignItemId=155124M173200|AllPinCount=4
|RECORD=41|OwnerIndex=280|OwnerPartId=-1|Location.X=1148|Location.Y=240|Color=8388608|FontID=6|IsHidden=T|Text=https://www.mouser.com/ds/2/445/155124M173200-1113601.pdf|Name=Datasheet Link|IsMirrored=T
|RECORD=41|OwnerIndex=280|IndexInSheet=1|OwnerPartId=-1|Location.X=1148|Location.Y=240|Color=8388608|FontID=1|IsHidden=T|Text=Wurth Elektronik|Name=Manufacturer_Name|IsMirrored=T
|RECORD=41|OwnerIndex=280|IndexInSheet=2|OwnerPartId=-1|Location.X=1148|Location.Y=240|Color=8388608|FontID=1|IsHidden=T|Text=155124M173200|Name=Manufacturer_Part_Number|IsMirrored=T
|RECORD=41|OwnerIndex=280|IndexInSheet=3|OwnerPartId=-1|Location.X=1148|Location.Y=240|Color=8388608|FontID=1|IsHidden=T|Text=710-155124M173200|Name=Mouser Part Number|IsMirrored=T
|RECORD=41|OwnerIndex=280|IndexInSheet=4|OwnerPartId=-1|Location.X=1148|Location.Y=240|Color=8388608|FontID=6|IsHidden=T|Text=https://www.mouser.co.uk/ProductDetail/Wurth-Elektronik/155124M173200?qs=5aG0NVq1C4xPhoUU07x4gQ%3D%3D|Name=Mouser Price/Stock|IsMirrored=T
|RECORD=41|OwnerIndex=280|IndexInSheet=5|OwnerPartId=-1|Location.X=1148|Location.Y=240|Color=8388608|FontID=1|IsHidden=T|Name=Arrow Part Number|IsMirrored=T
|RECORD=41|OwnerIndex=280|IndexInSheet=6|OwnerPartId=-1|Location.X=1148|Location.Y=240|Color=8388608|FontID=1|IsHidden=T|Name=Arrow Price/Stock|IsMirrored=T
|RECORD=14|OwnerIndex=280|IsNotAccesible=T|IndexInSheet=7|OwnerPartId=1|Location.X=1170|Location.Y=200|Corner.X=1230|Corner.Y=240|LineWidth=1|Color=128|AreaColor=11599871|IsSolid=T
|RECORD=2|OwnerIndex=280|OwnerPartId=1|FormalType=1|Electrical=7|PinConglomerate=56|PinLength=20|Location.X=1230|Location.Y=230|Name=ANODE|Designator=1|SwapIDPart=Ž&Ž||PinPropagationDelay=0.000000E+000
|RECORD=2|OwnerIndex=280|OwnerPartId=1|FormalType=1|Electrical=2|PinConglomerate=58|PinLength=20|Location.X=1170|Location.Y=210|Name=B|Designator=2|SwapIDPart=Ž&Ž||PinPropagationDelay=0.000000E+000
|RECORD=2|OwnerIndex=280|OwnerPartId=1|FormalType=1|Electrical=2|PinConglomerate=58|PinLength=20|Location.X=1170|Location.Y=220|Name=G|Designator=3|SwapIDPart=Ž&Ž||PinPropagationDelay=0.000000E+000
|RECORD=2|OwnerIndex=280|OwnerPartId=1|FormalType=1|Electrical=2|PinConglomerate=58|PinLength=20|Location.X=1170|Location.Y=230|Name=R|Designator=4|SwapIDPart=Ž&Ž||PinPropagationDelay=0.000000E+000
|RECORD=34|OwnerIndex=280|IndexInSheet=-1|OwnerPartId=-1|Location.X=1170|Location.Y=240|Color=8388608|FontID=1|Text=D18|Name=Designator|ReadOnlyState=1|IsMirrored=T
|RECORD=41|OwnerIndex=280|IndexInSheet=-1|OwnerPartId=-1|Location.X=1170|Location.Y=190|Color=8388608|FontID=1|Text=155124M173200|Name=Comment|IsMirrored=T
|RECORD=44|OwnerIndex=280
|RECORD=45|OwnerIndex=299|IndexInSheet=-1|ModelName=155124M173200|ModelType=PCBLIB|DatafileCount=1|ModelDatafile0=C:\Users\<user>\Documents\AltiumLL\SamacSys.PcbLib|ModelDatafileEntity0=155124M173200|ModelDatafileKind0=PCBLIB|IsCurrent=T
|RECORD=46|OwnerIndex=300
|RECORD=48|OwnerIndex=300
|RECORD=1|LibReference=IS32FL3207|PartCount=2|DisplayModeCount=1|IndexInSheet=47|OwnerPartId=-1|Location.X=680|Location.Y=500|CurrentPartId=1|LibraryPath=*|SourceLibraryName=IS32FL3207.SchLib|TargetFileName=*|AreaColor=11599871|Color=128|PartIDLocked=T|PinsMoveable=T|DesignItemId=IS32FL3207|AllPinCount=29
|RECORD=14|OwnerIndex=303|IsNotAccesible=T|OwnerPartId=1|Location.X=710|Location.Y=260|Corner.X=800|Corner.Y=500|Color=128|AreaColor=11599871|IsSolid=T
|RECORD=2|OwnerIndex=303|OwnerPartId=1|FormalType=1|PinConglomerate=26|PinLength=30|Location.X=710|Location.Y=430|Name=SDB|Designator=1|SwapIDPart=Ž&Ž||PinPropagationDelay=0.000000E+000
|RECORD=2|OwnerIndex=303|OwnerPartId=1|FormalType=1|PinConglomerate=26|PinLength=30|Location.X=710|Location.Y=460|Name=AD|Designator=2|SwapIDPart=Ž&Ž||PinPropagationDelay=0.000000E+000
|RECORD=2|OwnerIndex=303|OwnerPartId=1|FormalType=1|PinConglomerate=26|PinLength=30|Location.X=710|Location.Y=340|Name=VCC|Designator=3|SwapIDPart=Ž&Ž||PinPropagationDelay=0.000000E+000
|RECORD=2|OwnerIndex=303|OwnerPartId=1|FormalType=1|PinConglomerate=26|PinLength=30|Location.X=710|Location.Y=310|Name=GND|Designator=4|SwapIDPart=Ž&Ž||PinPropagationDelay=0.000000E+000
|RECORD=2|OwnerIndex=303|OwnerPartId=1|FormalType=1|PinConglomerate=26|PinLength=30|Location.X=710|Location.Y=410|Name=ISET|Designator=5|SwapIDPart=Ž&Ž||PinPropagationDelay=0.000000E+000
|RECORD=2|OwnerIndex=303|OwnerPartId=1|FormalType=1|PinConglomerate=26|PinLength=30|Location.X=710|Location.Y=490|Name=SDA|Designator=6|SwapIDPart=Ž&Ž||PinPropagationDelay=0.000000E+000
|RECORD=2|OwnerIndex=303|OwnerPartId=1|FormalType=1|PinConglomerate=26|PinLength=30|Location.X=710|Location.Y=480|Name=SCL|Designator=7|SwapIDPart=Ž&Ž||PinPropagationDelay=0.000000E+000
|RECORD=2|OwnerIndex=303|OwnerPartId=1|FormalType=1|PinConglomerate=24|PinLength=30|Location.X=800|Location.Y=490|Name=OUT1|Designator=8|SwapIDPart=Ž&Ž||PinPropagationDelay=0.000000E+000
|RECORD=2|OwnerIndex=303|OwnerPartId=1|FormalType=1|PinConglomerate=24|PinLength=30|Location.X=800|Location.Y=480|Name=OUT2|Designator=9|SwapIDPart=Ž&Ž||PinPropagationDelay=0.000000E+000
|RECORD=2|OwnerIndex=303|OwnerPartId=1|FormalType=1|PinConglomerate=24|PinLength=30|Location.X=800|Location.Y=470|Name=OUT3|Designator=10|SwapIDPart=Ž&Ž||PinPropagationDelay=0.000000E+000
|RECORD=2|OwnerIndex=303|OwnerPartId=1|FormalType=1|PinConglomerate=26|PinLength=30|Location.X=710|Location.Y=300|Name=GND|Designator=11|SwapIDPart=Ž&Ž||PinPropagationDelay=0.000000E+000
|RECORD=2|OwnerIndex=303|OwnerPartId=1|FormalType=1|PinConglomerate=24|PinLength=30|Location.X=800|Location.Y=450|Name=OUT4|Designator=12|SwapIDPart=Ž&Ž||PinPropagationDelay=0.000000E+000
|RECORD=2|OwnerIndex=303|OwnerPartId=1|FormalType=1|PinConglomerate=24|PinLength=30|Location.X=800|Location.Y=440|Name=OUT5|Designator=13|SwapIDPart=Ž&Ž||PinPropagationDelay=0.000000E+000
|RECORD=2|OwnerIndex=303|OwnerPartId=1|FormalType=1|PinConglomerate=24|PinLength=30|Location.X=800|Location.Y=430|Name=OUT6|Designator=14|SwapIDPart=Ž&Ž||PinPropagationDelay=0.000000E+000
|RECORD=2|OwnerIndex=303|OwnerPartId=1|FormalType=1|PinConglomerate=24|PinLength=30|Location.X=800|Location.Y=410|Name=OUT7|Designator=15|SwapIDPart=Ž&Ž||PinPropagationDelay=0.000000E+000
|RECORD=2|OwnerIndex=303|OwnerPartId=1|FormalType=1|PinConglomerate=24|PinLength=30|Location.X=800|Location.Y=400|Name=OUT8|Designator=16|SwapIDPart=Ž&Ž||PinPropagationDelay=0.000000E+000
|RECORD=2|OwnerIndex=303|OwnerPartId=1|FormalType=1|PinConglomerate=24|PinLength=30|Location.X=800|Location.Y=390|Name=OUT9|Designator=17|SwapIDPart=Ž&Ž||PinPropagationDelay=0.000000E+000
|RECORD=2|OwnerIndex=303|OwnerPartId=1|FormalType=1|PinConglomerate=26|PinLength=30|Location.X=710|Location.Y=290|Name=GND|Designator=18|SwapIDPart=Ž&Ž||PinPropagationDelay=0.000000E+000
|RECORD=2|OwnerIndex=303|OwnerPartId=1|FormalType=1|PinConglomerate=24|PinLength=30|Location.X=800|Location.Y=370|Name=OUT10|Designator=19|SwapIDPart=Ž&Ž||PinPropagationDelay=0.000000E+000
|RECORD=2|OwnerIndex=303|OwnerPartId=1|FormalType=1|PinConglomerate=24|PinLength=30|Location.X=800|Location.Y=360|Name=OUT11|Designator=20|SwapIDPart=Ž&Ž||PinPropagationDelay=0.000000E+000
|RECORD=2|OwnerIndex=303|OwnerPartId=1|FormalType=1|PinConglomerate=24|PinLength=30|Location.X=800|Location.Y=350|Name=OUT12|Designator=21|SwapIDPart=Ž&Ž||PinPropagationDelay=0.000000E+000
|RECORD=2|OwnerIndex=303|OwnerPartId=1|FormalType=1|PinConglomerate=24|PinLength=30|Location.X=800|Location.Y=330|Name=OUT13|Designator=22|SwapIDPart=Ž&Ž||PinPropagationDelay=0.000000E+000
|RECORD=2|OwnerIndex=303|OwnerPartId=1|FormalType=1|PinConglomerate=24|PinLength=30|Location.X=800|Location.Y=320|Name=OUT14|Designator=23|SwapIDPart=Ž&Ž||PinPropagationDelay=0.000000E+000
|RECORD=2|OwnerIndex=303|OwnerPartId=1|FormalType=1|PinConglomerate=24|PinLength=30|Location.X=800|Location.Y=310|Name=OUT15|Designator=24|SwapIDPart=Ž&Ž||PinPropagationDelay=0.000000E+000
|RECORD=2|OwnerIndex=303|OwnerPartId=1|FormalType=1|PinConglomerate=26|PinLength=30|Location.X=710|Location.Y=280|Name=GND|Designator=25|SwapIDPart=Ž&Ž||PinPropagationDelay=0.000000E+000
|RECORD=2|OwnerIndex=303|OwnerPartId=1|FormalType=1|PinConglomerate=24|PinLength=30|Location.X=800|Location.Y=290|Name=OUT16|Designator=26|SwapIDPart=Ž&Ž||PinPropagationDelay=0.000000E+000
|RECORD=2|OwnerIndex=303|OwnerPartId=1|FormalType=1|PinConglomerate=24|PinLength=30|Location.X=800|Location.Y=280|Name=OUT17|Designator=27|SwapIDPart=Ž&Ž||PinPropagationDelay=0.000000E+000
|RECORD=2|OwnerIndex=303|OwnerPartId=1|FormalType=1|PinConglomerate=24|PinLength=30|Location.X=800|Location.Y=270|Name=OUT18|Designator=28|SwapIDPart=Ž&Ž||PinPropagationDelay=0.000000E+000
|RECORD=2|OwnerIndex=303|OwnerPartId=1|FormalType=1|PinConglomerate=26|PinLength=30|Location.X=710|Location.Y=270|Name=EP|Designator=29|SwapIDPart=Ž&Ž||PinPropagationDelay=0.000000E+000
|RECORD=34|OwnerIndex=303|IndexInSheet=-1|OwnerPartId=-1|Location.X=710|Location.Y=500|Color=8388608|FontID=1|Text=U6|Name=Designator|ReadOnlyState=1
|RECORD=41|OwnerIndex=303|IndexInSheet=-1|OwnerPartId=-1|Location.X=710|Location.Y=250|Color=8388608|FontID=1|Text=IS32FL3207|Name=Comment
|RECORD=44|OwnerIndex=303
|RECORD=45|OwnerIndex=365|IndexInSheet=-1|ModelName=IS32FL3207|ModelType=PCBLIB|DatafileCount=1|ModelDatafileEntity0=IS32FL3207|ModelDatafileKind0=PCBLib|IsCurrent=T
|RECORD=46|OwnerIndex=366
|RECORD=48|OwnerIndex=366
|RECORD=17|IndexInSheet=48|OwnerPartId=-1|ShowNetName=T|Location.X=1280|Location.Y=600|Orientation=1|Color=128|FontID=1|Text=+3.3V
|RECORD=4|IndexInSheet=49|OwnerPartId=-1|Location.X=770|Location.Y=620|Color=8388608|FontID=5|Text=IO STATUS LEDS
|RECORD=4|IndexInSheet=50|OwnerPartId=-1|Location.X=1300|Location.Y=530|Color=8388608|FontID=5|Text=GNSS 1
|RECORD=4|IndexInSheet=51|OwnerPartId=-1|Location.X=1300|Location.Y=470|Color=8388608|FontID=5|Text=GNSS 2
|RECORD=4|IndexInSheet=52|OwnerPartId=-1|Location.X=1300|Location.Y=410|Color=8388608|FontID=5|Text=IO 1
|RECORD=4|IndexInSheet=53|OwnerPartId=-1|Location.X=1300|Location.Y=350|Color=8388608|FontID=5|Text=IO 2
|RECORD=4|IndexInSheet=54|OwnerPartId=-1|Location.X=1300|Location.Y=280|Color=8388608|FontID=5|Text=IO 3
|RECORD=4|IndexInSheet=55|OwnerPartId=-1|Location.X=1300|Location.Y=210|Color=8388608|FontID=5|Text=IO 4
|RECORD=1|LibReference=CAP|ComponentDescription=C0603X104K5RACAUTO|PartCount=2|DisplayModeCount=2|IndexInSheet=56|OwnerPartId=-1|Location.X=530|Location.Y=230|Orientation=1|CurrentPartId=1|SourceLibraryName=Altium Content Vault|TargetFileName=*|AreaColor=11599871|Color=128|PartIDLocked=F|DesignItemId=CMP-2006-00003-1|AllPinCount=2
|RECORD=2|OwnerIndex=377|OwnerPartId=1|OwnerPartDisplayMode=1|FormalType=1|Electrical=4|PinConglomerate=35|PinLength=10|Location.X=540|Location.Y=230|Name=1|Designator=1|PinPropagationDelay=0.000000E+000
|RECORD=2|OwnerIndex=377|OwnerPartId=1|OwnerPartDisplayMode=1|FormalType=1|Electrical=4|PinConglomerate=33|PinLength=10|Location.X=540|Location.Y=240|Name=2|Designator=2|PinPropagationDelay=0.000000E+000
|RECORD=13|OwnerIndex=377|IsNotAccesible=T|IndexInSheet=2|OwnerPartId=1|OwnerPartDisplayMode=1|Location.X=548|Location.Y=230|Corner.X=532|Corner.Y=230|LineWidth=1|Color=16711680
|RECORD=13|OwnerIndex=377|IsNotAccesible=T|IndexInSheet=3|OwnerPartId=1|OwnerPartDisplayMode=1|Location.X=540|Location.Y=234|Corner.X=540|Corner.Y=240|LineWidth=1|Color=16711680
|RECORD=12|OwnerIndex=377|IsNotAccesible=T|IndexInSheet=4|OwnerPartId=1|OwnerPartDisplayMode=1|Location.X=540|Location.Y=250|Radius=16|LineWidth=1|StartAngle=241.000|EndAngle=270.000|Color=16711680
|RECORD=12|OwnerIndex=377|IsNotAccesible=T|IndexInSheet=5|OwnerPartId=1|OwnerPartDisplayMode=1|Location.X=540|Location.Y=250|Radius=16|LineWidth=1|StartAngle=270.000|EndAngle=299.000|Color=16711680
|RECORD=2|OwnerIndex=377|OwnerPartId=1|FormalType=1|Electrical=4|PinConglomerate=35|PinLength=10|Location.X=540|Location.Y=230|Name=1|Designator=1|PinPropagationDelay=0.000000E+000
|RECORD=2|OwnerIndex=377|OwnerPartId=1|FormalType=1|Electrical=4|PinConglomerate=33|PinLength=10|Location.X=540|Location.Y=240|Name=2|Designator=2|PinPropagationDelay=0.000000E+000
|RECORD=13|OwnerIndex=377|IsNotAccesible=T|IndexInSheet=8|OwnerPartId=1|Location.X=532|Location.Y=237|Corner.X=548|Corner.Y=237|LineWidth=1|Color=16711680
|RECORD=13|OwnerIndex=377|IsNotAccesible=T|IndexInSheet=9|OwnerPartId=1|Location.X=548|Location.Y=233|Corner.X=532|Corner.Y=233|LineWidth=1|Color=16711680
|RECORD=6|OwnerIndex=377|IsNotAccesible=T|IndexInSheet=10|OwnerPartId=1|LineWidth=1|Color=16711680|LocationCount=2|X1=540|Y1=230|X2=540|Y2=233
|RECORD=6|OwnerIndex=377|IsNotAccesible=T|IndexInSheet=11|OwnerPartId=1|LineWidth=1|Color=16711680|LocationCount=2|X1=540|Y1=240|X2=540|Y2=237
|RECORD=41|OwnerIndex=377|IndexInSheet=12|OwnerPartId=-1|Location.X=531|Location.Y=252|Color=8388608|FontID=1|IsHidden=T|Text=Kemet|Name=Manufacturer
|RECORD=41|OwnerIndex=377|IndexInSheet=13|OwnerPartId=-1|Location.X=531|Location.Y=252|Color=8388608|FontID=1|IsHidden=T|Text=C0603X104K5RACAUTO|Name=Part Number
|RECORD=34|OwnerIndex=377|IndexInSheet=-1|OwnerPartId=-1|Location.X=549|Location.Y=231|Color=8388608|FontID=1|Text=C40|Name=Designator|ReadOnlyState=1
|RECORD=41|OwnerIndex=377|IndexInSheet=-1|OwnerPartId=-1|Location.X=549|Location.Y=221|Color=8388608|FontID=1|Text=0.1uF|Name=Comment
|RECORD=44|OwnerIndex=377
|RECORD=45|OwnerIndex=398|IndexInSheet=-1|Description=Chip Capacitor, 2-Leads, Body 1.60x0.80mm, IPC Low Density|UseComponentLibrary=T|ModelName=CAPC1608X87X45ML20T05|ModelType=PCBLIB|DatafileCount=1|ModelDatafileEntity0=CAPC1608X87X45ML20T05|ModelDatafileKind0=PCBLib|IsCurrent=T|DatalinksLocked=T|DatabaseDatalinksLocked=T
|RECORD=46|OwnerIndex=399
|RECORD=48|OwnerIndex=399
|RECORD=41|OwnerIndex=401|IndexInSheet=-1|OwnerPartId=-1|Color=8388608|FontID=1|Text=2D|Name=Available Preview Images
|RECORD=45|OwnerIndex=398|IndexInSheet=-1|Description=Chip Capacitor, 2-Leads, Body 1.60x0.80mm, IPC High Density|UseComponentLibrary=T|ModelName=CAPC1608X87X45LL20T05|ModelType=PCBLIB|DatafileCount=1|ModelDatafileEntity0=CAPC1608X87X45LL20T05|ModelDatafileKind0=PCBLib|DatalinksLocked=T|DatabaseDatalinksLocked=T
|RECORD=46|OwnerIndex=403
|RECORD=48|OwnerIndex=403
|RECORD=41|OwnerIndex=405|IndexInSheet=-1|OwnerPartId=-1|Color=8388608|FontID=1|Text=2D|Name=Available Preview Images
|RECORD=45|OwnerIndex=398|IndexInSheet=-1|Description=Chip Capacitor, 2-Leads, Body 1.60x0.80mm, IPC Medium Density|UseComponentLibrary=T|ModelName=CAPC1608X87X45NL20T05|ModelType=PCBLIB|DatafileCount=1|ModelDatafileEntity0=CAPC1608X87X45NL20T05|ModelDatafileKind0=PCBLib|DatalinksLocked=T|DatabaseDatalinksLocked=T
|RECORD=46|OwnerIndex=407
|RECORD=48|OwnerIndex=407
|RECORD=41|OwnerIndex=409|IndexInSheet=-1|OwnerPartId=-1|Color=8388608|FontID=1|Text=2D|Name=Available Preview Images
|RECORD=1|LibReference=e9c51b7dd13d4faca003ae77663ab08|ComponentDescription=CAP CER 1UF 25V X5R 0603|PartCount=2|DisplayModeCount=1|IndexInSheet=57|OwnerPartId=-1|Location.X=500|Location.Y=250|CurrentPartId=1|LibraryPath=*|SourceLibraryName=Altium Content Vault|TargetFileName=*|AreaColor=11599871|Color=128|PartIDLocked=T|DesignItemId=CMP-2006-02216-3|AllPinCount=2
|RECORD=2|OwnerIndex=411|OwnerPartId=1|Electrical=4|PinConglomerate=33|PinLength=7|Location.X=500|Location.Y=243|Name=1|Designator=1|PinName_PositionConglomerate=16|Name_CustomFontID=1|PinDesignator_PositionConglomerate=16|Designator_CustomFontID=1|PinPropagationDelay=0.000000E+000
|RECORD=2|OwnerIndex=411|OwnerPartId=1|Electrical=4|PinConglomerate=35|PinLength=6|Location.X=500|Location.Y=236|Name=2|Designator=2|PinName_PositionConglomerate=16|Name_CustomFontID=1|PinDesignator_PositionConglomerate=16|Designator_CustomFontID=1|PinPropagationDelay=0.000000E+000
|RECORD=13|OwnerIndex=411|IsNotAccesible=T|IndexInSheet=2|OwnerPartId=1|Location.X=510|Location.Y=243|Corner.X=490|Corner.Y=243|LineWidth=1|Color=16711680
|RECORD=13|OwnerIndex=411|IsNotAccesible=T|IndexInSheet=3|OwnerPartId=1|Location.X=510|Location.Y=237|Corner.X=490|Corner.Y=237|LineWidth=1|Color=16711680
|RECORD=13|OwnerIndex=411|IsNotAccesible=T|IndexInSheet=4|OwnerPartId=1|Location.X=500|Location.Y=243|Corner.X=500|Corner.Y=246|LineWidth=1|Color=16711680
|RECORD=13|OwnerIndex=411|IsNotAccesible=T|IndexInSheet=5|OwnerPartId=1|Location.X=500|Location.Y=236|Corner.X=500|Corner.Y=235|LineWidth=1|Color=16711680
|RECORD=41|OwnerIndex=411|IndexInSheet=6|OwnerPartId=-1|Location.X=489|Location.Y=252|Color=8388608|FontID=1|IsHidden=T|Text=Tin|Name=Contact Plating
|RECORD=41|OwnerIndex=411|IndexInSheet=7|OwnerPartId=-1|Location.X=489|Location.Y=252|Color=8388608|FontID=1|IsHidden=T|Text=2|Name=Number of Pins
|RECORD=41|OwnerIndex=411|IndexInSheet=8|OwnerPartId=-1|Location.X=489|Location.Y=252|Color=8388608|FontID=1|IsHidden=T|Text=Lead Free|Name=Lead Free
|RECORD=41|OwnerIndex=411|IndexInSheet=9|OwnerPartId=-1|Location.X=489|Location.Y=252|Color=8388608|FontID=1|IsHidden=T|Text=0.8mm|Name=Depth
|RECORD=41|OwnerIndex=411|IndexInSheet=10|OwnerPartId=-1|Location.X=489|Location.Y=252|Color=8388608|FontID=1|IsHidden=T|Text=1.6mm|Name=Length
|RECORD=41|OwnerIndex=411|IndexInSheet=11|OwnerPartId=-1|Location.X=489|Location.Y=252|Color=8388608|FontID=1|IsHidden=T|Text=Surface Mount|Name=Mount
|RECORD=41|OwnerIndex=411|IndexInSheet=12|OwnerPartId=-1|Location.X=489|Location.Y=252|Color=8388608|FontID=1|IsHidden=T|Text=1608|Name=Case Code (Metric)
|RECORD=41|OwnerIndex=411|IndexInSheet=13|OwnerPartId=-1|Location.X=489|Location.Y=252|Color=8388608|FontID=1|IsHidden=T|Text=85°C|Name=Max Operating Temperature
|RECORD=41|OwnerIndex=411|IndexInSheet=14|OwnerPartId=-1|Location.X=489|Location.Y=252|Color=8388608|FontID=1|IsHidden=T|Text=25V|Name=Voltage
|RECORD=41|OwnerIndex=411|IndexInSheet=15|OwnerPartId=-1|Location.X=489|Location.Y=252|Color=8388608|FontID=1|IsHidden=T|Text=25V|Name=Voltage Rating (DC)
|RECORD=41|OwnerIndex=411|IndexInSheet=16|OwnerPartId=-1|Location.X=489|Location.Y=252|Color=8388608|FontID=1|IsHidden=T|Text=Ceramic|Name=Dielectric Material
|RECORD=41|OwnerIndex=411|IndexInSheet=17|OwnerPartId=-1|Location.X=489|Location.Y=252|Color=8388608|FontID=1|IsHidden=T|Text=No SVHC|Name=REACH SVHC
|RECORD=41|OwnerIndex=411|IndexInSheet=18|OwnerPartId=-1|Location.X=489|Location.Y=252|Color=8388608|FontID=1|IsHidden=T|Text=0.8mm|Name=Height
|RECORD=41|OwnerIndex=411|IndexInSheet=19|OwnerPartId=-1|Location.X=489|Location.Y=252|Color=8388608|FontID=1|IsHidden=T|Text=C0603C|Name=Series
|RECORD=41|OwnerIndex=411|IndexInSheet=20|OwnerPartId=-1|Location.X=489|Location.Y=252|Color=8388608|FontID=1|IsHidden=T|Text=0603|Name=Case/Package
|RECORD=41|OwnerIndex=411|IndexInSheet=21|OwnerPartId=-1|Location.X=489|Location.Y=252|Color=8388608|FontID=1|IsHidden=T|Text=0603|Name=Case Code (Imperial)
|RECORD=41|OwnerIndex=411|IndexInSheet=22|OwnerPartId=-1|Location.X=489|Location.Y=252|Color=8388608|FontID=1|IsHidden=T|Text=1uF|Name=Capacitance
|RECORD=41|OwnerIndex=411|IndexInSheet=23|OwnerPartId=-1|Location.X=489|Location.Y=252|Color=8388608|FontID=1|IsHidden=T|Text=Yes|Name=RoHS Compliant
|RECORD=41|OwnerIndex=411|IndexInSheet=24|OwnerPartId=-1|Location.X=489|Location.Y=252|Color=8388608|FontID=1|IsHidden=T|Text=X5R|Name=Dielectric
|RECORD=41|OwnerIndex=411|IndexInSheet=25|OwnerPartId=-1|Location.X=489|Location.Y=252|Color=8388608|FontID=1|IsHidden=T|Text=Tape and Reel|Name=Packaging
|RECORD=41|OwnerIndex=411|IndexInSheet=26|OwnerPartId=-1|Location.X=489|Location.Y=252|Color=8388608|FontID=1|IsHidden=T|Text=Flat|Name=Construction
|RECORD=41|OwnerIndex=411|IndexInSheet=27|OwnerPartId=-1|Location.X=489|Location.Y=252|Color=8388608|FontID=1|IsHidden=T|Text=0.034inch|Name=Thickness
|RECORD=41|OwnerIndex=411|IndexInSheet=28|OwnerPartId=-1|Location.X=489|Location.Y=252|Color=8388608|FontID=1|IsHidden=T|Text=25V|Name=Voltage Rating
|RECORD=41|OwnerIndex=411|IndexInSheet=29|OwnerPartId=-1|Location.X=489|Location.Y=252|Color=8388608|FontID=1|IsHidden=T|Text=No|Name=Radiation Hardening
|RECORD=41|OwnerIndex=411|IndexInSheet=30|OwnerPartId=-1|Location.X=489|Location.Y=252|Color=8388608|FontID=1|IsHidden=T|Text=0.031inch|Name=Width
|RECORD=41|OwnerIndex=411|IndexInSheet=31|OwnerPartId=-1|Location.X=489|Location.Y=252|Color=8388608|FontID=1|IsHidden=T|Text=-55°C|Name=Min Operating Temperature
|RECORD=41|OwnerIndex=411|IndexInSheet=32|OwnerPartId=-1|Location.X=489|Location.Y=252|Color=8388608|FontID=1|IsHidden=T|Text=SMD/SMT|Name=Termination
|RECORD=41|OwnerIndex=411|IndexInSheet=33|OwnerPartId=-1|Location.X=489|Location.Y=252|Color=8388608|FontID=1|IsHidden=T|Text=10%|Name=Tolerance
|RECORD=41|OwnerIndex=411|IndexInSheet=34|OwnerPartId=-1|Location.X=489|Location.Y=252|Color=8388608|FontID=1|IsHidden=T|Text=4000|Name=Package Quantity
|RECORD=34|OwnerIndex=411|IndexInSheet=-1|OwnerPartId=-1|Location.X=511|Location.Y=237|Color=8388608|FontID=1|Text=C38|Name=Designator|ReadOnlyState=1
|RECORD=41|OwnerIndex=411|IndexInSheet=-1|OwnerPartId=1|Location.X=511|Location.Y=227|Color=8388608|FontID=1|Text=1uF|Name=Comment
|RECORD=44|OwnerIndex=411
|RECORD=45|OwnerIndex=451|IndexInSheet=-1|UseComponentLibrary=T|ModelName=FP-C0603C105K3PACTU-MFG|ModelType=PCBLIB|DatafileCount=1|ModelDatafileEntity0=FP-C0603C105K3PACTU-MFG|ModelDatafileKind0=PCBLib|IsCurrent=T|DatalinksLocked=T|DatabaseDatalinksLocked=T
|RECORD=46|OwnerIndex=452
|RECORD=48|OwnerIndex=452
|RECORD=45|OwnerIndex=451|IndexInSheet=-1|UseComponentLibrary=T|ModelName=FP-C0603C105K3PACTU-IPC_C|ModelType=PCBLIB|DatafileCount=1|ModelDatafileEntity0=FP-C0603C105K3PACTU-IPC_C|ModelDatafileKind0=PCBLib|DatalinksLocked=T|DatabaseDatalinksLocked=T
|RECORD=46|OwnerIndex=455
|RECORD=48|OwnerIndex=455
|RECORD=45|OwnerIndex=451|IndexInSheet=-1|UseComponentLibrary=T|ModelName=FP-C0603C105K3PACTU-IPC_B|ModelType=PCBLIB|DatafileCount=1|ModelDatafileEntity0=FP-C0603C105K3PACTU-IPC_B|ModelDatafileKind0=PCBLib|DatalinksLocked=T|DatabaseDatalinksLocked=T
|RECORD=46|OwnerIndex=458
|RECORD=48|OwnerIndex=458
|RECORD=45|OwnerIndex=451|IndexInSheet=-1|UseComponentLibrary=T|ModelName=FP-C0603C105K3PACTU-IPC_A|ModelType=PCBLIB|DatafileCount=1|ModelDatafileEntity0=FP-C0603C105K3PACTU-IPC_A|ModelDatafileKind0=PCBLib|DatalinksLocked=T|DatabaseDatalinksLocked=T
|RECORD=46|OwnerIndex=461
|RECORD=48|OwnerIndex=461
|RECORD=1|LibReference=1029c3af85768c4190bb7ad29bc67b5|ComponentDescription=RES SMD 100K OHM 1% 1/10W 0603|PartCount=2|DisplayModeCount=1|IndexInSheet=58|OwnerPartId=-1|Location.X=400|Location.Y=210|Orientation=1|CurrentPartId=1|LibraryPath=*|SourceLibraryName=Altium Content Vault|TargetFileName=*|AreaColor=11599871|Color=128|PartIDLocked=T|DesignItemId=CMP-2100-03662-2|AllPinCount=2
|RECORD=2|OwnerIndex=464|OwnerPartId=1|Electrical=4|PinConglomerate=35|PinLength=20|Location.X=400|Location.Y=230|Name=1|Designator=1|PinPropagationDelay=0.000000E+000
|RECORD=2|OwnerIndex=464|OwnerPartId=1|Electrical=4|PinConglomerate=33|PinLength=20|Location.X=400|Location.Y=260|Name=2|Designator=2|PinPropagationDelay=0.000000E+000
|RECORD=13|OwnerIndex=464|IsNotAccesible=T|IndexInSheet=2|OwnerPartId=1|Location.X=400|Location.Y=230|Corner.X=395|Corner.Y=233|LineWidth=1|Color=16711680
|RECORD=13|OwnerIndex=464|IsNotAccesible=T|IndexInSheet=3|OwnerPartId=1|Location.X=395|Location.Y=233|Corner.X=405|Corner.Y=238|LineWidth=1|Color=16711680
|RECORD=13|OwnerIndex=464|IsNotAccesible=T|IndexInSheet=4|OwnerPartId=1|Location.X=405|Location.Y=238|Corner.X=395|Corner.Y=243|LineWidth=1|Color=16711680
|RECORD=13|OwnerIndex=464|IsNotAccesible=T|IndexInSheet=5|OwnerPartId=1|Location.X=395|Location.Y=243|Corner.X=405|Corner.Y=248|LineWidth=1|Color=16711680
|RECORD=13|OwnerIndex=464|IsNotAccesible=T|IndexInSheet=6|OwnerPartId=1|Location.X=405|Location.Y=248|Corner.X=395|Corner.Y=253|LineWidth=1|Color=16711680
|RECORD=13|OwnerIndex=464|IsNotAccesible=T|IndexInSheet=7|OwnerPartId=1|Location.X=395|Location.Y=253|Corner.X=405|Corner.Y=258|LineWidth=1|Color=16711680
|RECORD=13|OwnerIndex=464|IsNotAccesible=T|IndexInSheet=8|OwnerPartId=1|Location.X=405|Location.Y=258|Corner.X=400|Corner.Y=260|LineWidth=1|Color=16711680
|RECORD=13|OwnerIndex=464|IsNotAccesible=T|IndexInSheet=9|OwnerPartId=1|Location.X=400|Location.Y=230|Corner.X=400|Corner.Y=227|LineWidth=1|Color=16711680
|RECORD=13|OwnerIndex=464|IsNotAccesible=T|IndexInSheet=10|OwnerPartId=1|Location.X=400|Location.Y=260|Corner.X=400|Corner.Y=263|LineWidth=1|Color=16711680
|RECORD=41|OwnerIndex=464|IndexInSheet=11|OwnerPartId=-1|Location.X=394|Location.Y=282|Color=8388608|FontID=1|IsHidden=T|Text=1.6mm|Name=Length
|RECORD=41|OwnerIndex=464|IndexInSheet=12|OwnerPartId=-1|Location.X=394|Location.Y=282|Color=8388608|FontID=1|IsHidden=T|Text=Lead Free|Name=Lead Free
|RECORD=41|OwnerIndex=464|IndexInSheet=13|OwnerPartId=-1|Location.X=394|Location.Y=282|Color=8388608|FontID=1|IsHidden=T|Text=2|Name=Number of Terminations
|RECORD=41|OwnerIndex=464|IndexInSheet=14|OwnerPartId=-1|Location.X=394|Location.Y=282|Color=8388608|FontID=1|IsHidden=T|Text=50V|Name=Voltage Rating (DC)
|RECORD=41|OwnerIndex=464|IndexInSheet=15|OwnerPartId=-1|Location.X=394|Location.Y=282|Color=8388608|FontID=1|IsHidden=T|Text=Tape and Reel|Name=Packaging
|RECORD=41|OwnerIndex=464|IndexInSheet=16|OwnerPartId=-1|Location.X=394|Location.Y=282|Color=8388608|FontID=1|IsHidden=T|Text=50V|Name=Voltage Rating
|RECORD=41|OwnerIndex=464|IndexInSheet=17|OwnerPartId=-1|Location.X=394|Location.Y=282|Color=8388608|FontID=1|IsHidden=T|Text=SMD/SMT|Name=Termination
|RECORD=41|OwnerIndex=464|IndexInSheet=18|OwnerPartId=-1|Location.X=394|Location.Y=282|Color=8388608|FontID=1|IsHidden=T|Text=0.8mm|Name=Width
|RECORD=41|OwnerIndex=464|IndexInSheet=19|OwnerPartId=-1|Location.X=394|Location.Y=282|Color=8388608|FontID=1|IsHidden=T|Text=100kR|Name=Resistance
|RECORD=41|OwnerIndex=464|IndexInSheet=20|OwnerPartId=-1|Location.X=394|Location.Y=282|Color=8388608|FontID=1|IsHidden=T|Text=Thick Film|Name=Resistor Type
|RECORD=41|OwnerIndex=464|IndexInSheet=21|OwnerPartId=-1|Location.X=394|Location.Y=282|Color=8388608|FontID=1|IsHidden=T|Text=100mW|Name=Max Power Dissipation
|RECORD=41|OwnerIndex=464|IndexInSheet=22|OwnerPartId=-1|Location.X=394|Location.Y=282|Color=8388608|FontID=1|IsHidden=T|Text=1%|Name=Resistance Tolerance
|RECORD=41|OwnerIndex=464|IndexInSheet=23|OwnerPartId=-1|Location.X=394|Location.Y=282|Color=8388608|FontID=1|IsHidden=T|Text=Moisture Resistant|Name=Features
|RECORD=41|OwnerIndex=464|IndexInSheet=24|OwnerPartId=-1|Location.X=394|Location.Y=282|Color=8388608|FontID=1|IsHidden=T|Text=0.45mm|Name=Height
|RECORD=41|OwnerIndex=464|IndexInSheet=25|OwnerPartId=-1|Location.X=394|Location.Y=282|Color=8388608|FontID=1|IsHidden=T|Text=Rectangular|Name=Construction
|RECORD=41|OwnerIndex=464|IndexInSheet=26|OwnerPartId=-1|Location.X=394|Location.Y=282|Color=8388608|FontID=1|IsHidden=T|Text=0603|Name=Case/Package
|RECORD=41|OwnerIndex=464|IndexInSheet=27|OwnerPartId=-1|Location.X=394|Location.Y=282|Color=8388608|FontID=1|IsHidden=T|Text=Not|Name=Military Standard
|RECORD=41|OwnerIndex=464|IndexInSheet=28|OwnerPartId=-1|Location.X=394|Location.Y=282|Color=8388608|FontID=1|IsHidden=T|Text=0603|Name=Case Code (Imperial)
|RECORD=41|OwnerIndex=464|IndexInSheet=29|OwnerPartId=-1|Location.X=394|Location.Y=282|Color=8388608|FontID=1|IsHidden=T|Text=100ppm/°C|Name=Temperature Coefficient
|RECORD=41|OwnerIndex=464|IndexInSheet=30|OwnerPartId=-1|Location.X=394|Location.Y=282|Color=8388608|FontID=1|IsHidden=T|Text=RC|Name=Series
|RECORD=41|OwnerIndex=464|IndexInSheet=31|OwnerPartId=-1|Location.X=394|Location.Y=282|Color=8388608|FontID=1|IsHidden=T|Text=THICK FILM|Name=Technology
|RECORD=41|OwnerIndex=464|IndexInSheet=32|OwnerPartId=-1|Location.X=394|Location.Y=282|Color=8388608|FontID=1|IsHidden=T|Text=0.8mm|Name=Depth
|RECORD=41|OwnerIndex=464|IndexInSheet=33|OwnerPartId=-1|Location.X=394|Location.Y=282|Color=8388608|FontID=1|IsHidden=T|Text=Yes|Name=RoHS Compliant
|RECORD=41|OwnerIndex=464|IndexInSheet=34|OwnerPartId=-1|Location.X=394|Location.Y=282|Color=8388608|FontID=1|IsHidden=T|Text=75V|Name=Working Voltage
|RECORD=41|OwnerIndex=464|IndexInSheet=35|OwnerPartId=-1|Location.X=394|Location.Y=282|Color=8388608|FontID=1|IsHidden=T|Text=No SVHC|Name=REACH SVHC
|RECORD=41|OwnerIndex=464|IndexInSheet=36|OwnerPartId=-1|Location.X=394|Location.Y=282|Color=8388608|FontID=1|IsHidden=T|Text=-55°C|Name=Min Operating Temperature
|RECORD=41|OwnerIndex=464|IndexInSheet=37|OwnerPartId=-1|Location.X=394|Location.Y=282|Color=8388608|FontID=1|IsHidden=T|Text=1608|Name=Case Code (Metric)
|RECORD=41|OwnerIndex=464|IndexInSheet=38|OwnerPartId=-1|Location.X=394|Location.Y=282|Color=8388608|FontID=1|IsHidden=T|Text=155°C|Name=Max Operating Temperature
|RECORD=41|OwnerIndex=464|IndexInSheet=39|OwnerPartId=-1|Location.X=394|Location.Y=282|Color=8388608|FontID=1|IsHidden=T|Text=100mW|Name=Power Rating
|RECORD=41|OwnerIndex=464|IndexInSheet=40|OwnerPartId=-1|Location.X=394|Location.Y=282|Color=8388608|FontID=1|IsHidden=T|Text=2|Name=Number of Pins
|RECORD=41|OwnerIndex=464|IndexInSheet=41|OwnerPartId=-1|Location.X=394|Location.Y=282|Color=8388608|FontID=1|IsHidden=T|Text=1%|Name=Tolerance
|RECORD=34|OwnerIndex=464|IndexInSheet=-1|OwnerPartId=-1|Location.X=406|Location.Y=254|Color=8388608|FontID=1|Text=R40|Name=Designator|ReadOnlyState=1
|RECORD=41|OwnerIndex=464|IndexInSheet=-1|OwnerPartId=1|Location.X=406|Location.Y=244|Color=8388608|FontID=1|Text=100k|Name=Comment
|RECORD=44|OwnerIndex=464
|RECORD=45|OwnerIndex=511|IndexInSheet=-1|UseComponentLibrary=T|ModelName=FP-RC0603-0_55-MFG|ModelType=PCBLIB|DatafileCount=1|ModelDatafileEntity0=FP-RC0603-0_55-MFG|ModelDatafileKind0=PCBLib|IsCurrent=T|DatalinksLocked=T|DatabaseDatalinksLocked=T
|RECORD=46|OwnerIndex=512
|RECORD=48|OwnerIndex=512
|RECORD=45|OwnerIndex=511|IndexInSheet=-1|UseComponentLibrary=T|ModelName=FP-RC0603-0_55-IPC_C|ModelType=PCBLIB|DatafileCount=1|ModelDatafileEntity0=FP-RC0603-0_55-IPC_C|ModelDatafileKind0=PCBLib|DatalinksLocked=T|DatabaseDatalinksLocked=T
|RECORD=46|OwnerIndex=515
|RECORD=48|OwnerIndex=515
|RECORD=45|OwnerIndex=511|IndexInSheet=-1|UseComponentLibrary=T|ModelName=FP-RC0603-0_55-IPC_B|ModelType=PCBLIB|DatafileCount=1|ModelDatafileEntity0=FP-RC0603-0_55-IPC_B|ModelDatafileKind0=PCBLib|DatalinksLocked=T|DatabaseDatalinksLocked=T
|RECORD=46|OwnerIndex=518
|RECORD=48|OwnerIndex=518
|RECORD=45|OwnerIndex=511|IndexInSheet=-1|UseComponentLibrary=T|ModelName=FP-RC0603-0_55-IPC_A|ModelType=PCBLIB|DatafileCount=1|ModelDatafileEntity0=FP-RC0603-0_55-IPC_A|ModelDatafileKind0=PCBLib|DatalinksLocked=T|DatabaseDatalinksLocked=T
|RECORD=46|OwnerIndex=521
|RECORD=48|OwnerIndex=521
|RECORD=17|IndexInSheet=59|OwnerPartId=-1|Style=4|ShowNetName=T|Location.X=540|Location.Y=200|Orientation=3|Color=128|FontID=1|Text=GND
|RECORD=17|IndexInSheet=60|OwnerPartId=-1|Style=4|ShowNetName=T|Location.X=500|Location.Y=200|Orientation=3|Color=128|FontID=1|Text=GND
|RECORD=17|IndexInSheet=61|OwnerPartId=-1|Style=4|ShowNetName=T|Location.X=650|Location.Y=200|Orientation=3|Color=128|FontID=1|Text=GND
|RECORD=1|LibReference=CAP|ComponentDescription=C0603X104K5RACAUTO|PartCount=2|DisplayModeCount=2|IndexInSheet=62|OwnerPartId=-1|Location.X=430|Location.Y=230|Orientation=1|CurrentPartId=1|SourceLibraryName=Altium Content Vault|TargetFileName=*|AreaColor=11599871|Color=128|PartIDLocked=F|DesignItemId=CMP-2006-00003-1|AllPinCount=2
|RECORD=2|OwnerIndex=527|OwnerPartId=1|OwnerPartDisplayMode=1|FormalType=1|Electrical=4|PinConglomerate=35|PinLength=10|Location.X=440|Location.Y=230|Name=1|Designator=1|PinPropagationDelay=0.000000E+000
|RECORD=2|OwnerIndex=527|OwnerPartId=1|OwnerPartDisplayMode=1|FormalType=1|Electrical=4|PinConglomerate=33|PinLength=10|Location.X=440|Location.Y=240|Name=2|Designator=2|PinPropagationDelay=0.000000E+000
|RECORD=13|OwnerIndex=527|IsNotAccesible=T|IndexInSheet=2|OwnerPartId=1|OwnerPartDisplayMode=1|Location.X=448|Location.Y=230|Corner.X=432|Corner.Y=230|LineWidth=1|Color=16711680
|RECORD=13|OwnerIndex=527|IsNotAccesible=T|IndexInSheet=3|OwnerPartId=1|OwnerPartDisplayMode=1|Location.X=440|Location.Y=234|Corner.X=440|Corner.Y=240|LineWidth=1|Color=16711680
|RECORD=12|OwnerIndex=527|IsNotAccesible=T|IndexInSheet=4|OwnerPartId=1|OwnerPartDisplayMode=1|Location.X=440|Location.Y=250|Radius=16|LineWidth=1|StartAngle=241.000|EndAngle=270.000|Color=16711680
|RECORD=12|OwnerIndex=527|IsNotAccesible=T|IndexInSheet=5|OwnerPartId=1|OwnerPartDisplayMode=1|Location.X=440|Location.Y=250|Radius=16|LineWidth=1|StartAngle=270.000|EndAngle=299.000|Color=16711680
|RECORD=2|OwnerIndex=527|OwnerPartId=1|FormalType=1|Electrical=4|PinConglomerate=35|PinLength=10|Location.X=440|Location.Y=230|Name=1|Designator=1|PinPropagationDelay=0.000000E+000
|RECORD=2|OwnerIndex=527|OwnerPartId=1|FormalType=1|Electrical=4|PinConglomerate=33|PinLength=10|Location.X=440|Location.Y=240|Name=2|Designator=2|PinPropagationDelay=0.000000E+000
|RECORD=13|OwnerIndex=527|IsNotAccesible=T|IndexInSheet=8|OwnerPartId=1|Location.X=432|Location.Y=237|Corner.X=448|Corner.Y=237|LineWidth=1|Color=16711680
|RECORD=13|OwnerIndex=527|IsNotAccesible=T|IndexInSheet=9|OwnerPartId=1|Location.X=448|Location.Y=233|Corner.X=432|Corner.Y=233|LineWidth=1|Color=16711680
|RECORD=6|OwnerIndex=527|IsNotAccesible=T|IndexInSheet=10|OwnerPartId=1|LineWidth=1|Color=16711680|LocationCount=2|X1=440|Y1=230|X2=440|Y2=233
|RECORD=6|OwnerIndex=527|IsNotAccesible=T|IndexInSheet=11|OwnerPartId=1|LineWidth=1|Color=16711680|LocationCount=2|X1=440|Y1=240|X2=440|Y2=237
|RECORD=41|OwnerIndex=527|IndexInSheet=12|OwnerPartId=-1|Location.X=431|Location.Y=252|Color=8388608|FontID=1|IsHidden=T|Text=Kemet|Name=Manufacturer
|RECORD=41|OwnerIndex=527|IndexInSheet=13|OwnerPartId=-1|Location.X=431|Location.Y=252|Color=8388608|FontID=1|IsHidden=T|Text=C0603X104K5RACAUTO|Name=Part Number
|RECORD=34|OwnerIndex=527|IndexInSheet=-1|OwnerPartId=-1|Location.X=449|Location.Y=231|Color=8388608|FontID=1|Text=C39|Name=Designator|ReadOnlyState=1
|RECORD=41|OwnerIndex=527|IndexInSheet=-1|OwnerPartId=-1|Location.X=449|Location.Y=221|Color=8388608|FontID=1|Text=0.1uF|Name=Comment
|RECORD=44|OwnerIndex=527
|RECORD=45|OwnerIndex=548|IndexInSheet=-1|Description=Chip Capacitor, 2-Leads, Body 1.60x0.80mm, IPC Low Density|UseComponentLibrary=T|ModelName=CAPC1608X87X45ML20T05|ModelType=PCBLIB|DatafileCount=1|ModelDatafileEntity0=CAPC1608X87X45ML20T05|ModelDatafileKind0=PCBLib|IsCurrent=T|DatalinksLocked=T|DatabaseDatalinksLocked=T
|RECORD=46|OwnerIndex=549
|RECORD=48|OwnerIndex=549
|RECORD=41|OwnerIndex=551|IndexInSheet=-1|OwnerPartId=-1|Color=8388608|FontID=1|Text=2D|Name=Available Preview Images
|RECORD=45|OwnerIndex=548|IndexInSheet=-1|Description=Chip Capacitor, 2-Leads, Body 1.60x0.80mm, IPC High Density|UseComponentLibrary=T|ModelName=CAPC1608X87X45LL20T05|ModelType=PCBLIB|DatafileCount=1|ModelDatafileEntity0=CAPC1608X87X45LL20T05|ModelDatafileKind0=PCBLib|DatalinksLocked=T|DatabaseDatalinksLocked=T
|RECORD=46|OwnerIndex=553
|RECORD=48|OwnerIndex=553
|RECORD=41|OwnerIndex=555|IndexInSheet=-1|OwnerPartId=-1|Color=8388608|FontID=1|Text=2D|Name=Available Preview Images
|RECORD=45|OwnerIndex=548|IndexInSheet=-1|Description=Chip Capacitor, 2-Leads, Body 1.60x0.80mm, IPC Medium Density|UseComponentLibrary=T|ModelName=CAPC1608X87X45NL20T05|ModelType=PCBLIB|DatafileCount=1|ModelDatafileEntity0=CAPC1608X87X45NL20T05|ModelDatafileKind0=PCBLib|DatalinksLocked=T|DatabaseDatalinksLocked=T
|RECORD=46|OwnerIndex=557
|RECORD=48|OwnerIndex=557
|RECORD=41|OwnerIndex=559|IndexInSheet=-1|OwnerPartId=-1|Color=8388608|FontID=1|Text=2D|Name=Available Preview Images
|RECORD=17|IndexInSheet=63|OwnerPartId=-1|Style=4|ShowNetName=T|Location.X=440|Location.Y=200|Orientation=3|Color=128|FontID=1|Text=GND
|RECORD=17|IndexInSheet=64|OwnerPartId=-1|Style=4|ShowNetName=T|Location.X=400|Location.Y=200|Orientation=3|Color=128|FontID=1|Text=GND
|RECORD=17|IndexInSheet=65|OwnerPartId=-1|ShowNetName=T|Location.X=500|Location.Y=510|Orientation=1|Color=128|FontID=1|Text=+3.3V
|RECORD=17|IndexInSheet=66|OwnerPartId=-1|ShowNetName=T|Location.X=530|Location.Y=510|Orientation=1|Color=128|FontID=1|Text=+3.3V
|RECORD=4|IndexInSheet=67|OwnerPartId=-1|Location.X=800|Location.Y=600|Color=8388608|FontID=7|Text=LED DRIVER (0x6E)
|RECORD=17|IndexInSheet=68|OwnerPartId=-1|ShowNetName=T|Location.X=580|Location.Y=490|Orientation=2|Color=255|FontID=1|Text=SDA|IsCrossSheetConnector=T
|RECORD=17|IndexInSheet=69|OwnerPartId=-1|ShowNetName=T|Location.X=580|Location.Y=480|Orientation=2|Color=255|FontID=1|Text=SCL|IsCrossSheetConnector=T
|RECORD=1|LibReference=RES-2|ComponentDescription=Precision Thick Film Chip Resistor, 4.7 KOhm, +/- 1%, -55 to 155 degC, 0603 (1608 Metric), RoHS, Tape and Reel ERJ-3EKF4701V|PartCount=2|DisplayModeCount=1|IndexInSheet=70|OwnerPartId=-1|Location.X=600|Location.Y=230|Orientation=1|CurrentPartId=1|LibraryPath=*|SourceLibraryName=Altium Content Vault|TargetFileName=*|AreaColor=11599871|Color=128|PartIDLocked=T|DesignItemId=CMP-1012-00586-3|AllPinCount=2
|RECORD=2|OwnerIndex=568|OwnerPartId=1|FormalType=1|Electrical=4|PinConglomerate=33|PinLength=10|Location.X=600|Location.Y=250|Name=2|Designator=2|PinPropagationDelay=0.000000E+000
|RECORD=2|OwnerIndex=568|OwnerPartId=1|FormalType=1|Electrical=4|PinConglomerate=35|PinLength=10|Location.X=600|Location.Y=230|Name=1|Designator=1|PinPropagationDelay=0.000000E+000
|RECORD=6|OwnerIndex=568|IsNotAccesible=T|IndexInSheet=2|OwnerPartId=1|LineWidth=1|Color=16711680|LocationCount=10|X1=600|Y1=250|X2=600|Y2=246|X3=602|Y3=245|X4=598|Y4=243|X5=602|Y5=241|X6=598|Y6=239|X7=602|Y7=237|X8=598|Y8=235|X9=600|Y9=234|X10=600|Y10=230
|RECORD=41|OwnerIndex=568|IndexInSheet=3|OwnerPartId=-1|Location.X=597|Location.Y=262|Color=8388608|FontID=1|IsHidden=T|Text=220 Ohm|Name=Resistance
|RECORD=41|OwnerIndex=568|IndexInSheet=4|OwnerPartId=-1|Location.X=597|Location.Y=262|Color=8388608|FontID=1|IsHidden=T|Text=0603|Name=PackageReference
|RECORD=41|OwnerIndex=568|IndexInSheet=5|OwnerPartId=-1|Location.X=597|Location.Y=262|Color=8388608|FontID=1|IsHidden=T|Text=50 V|Name=Voltage Rating
|RECORD=41|OwnerIndex=568|IndexInSheet=6|OwnerPartId=-1|Location.X=597|Location.Y=262|Color=8388608|FontID=1|IsHidden=T|Text=125 degC|Name=Max Operating Temperature
|RECORD=41|OwnerIndex=568|IndexInSheet=7|OwnerPartId=-1|Location.X=597|Location.Y=262|Color=8388608|FontID=1|IsHidden=T|Text=4|Name=Elements
|RECORD=41|OwnerIndex=568|IndexInSheet=8|OwnerPartId=-1|Location.X=597|Location.Y=262|Color=8388608|FontID=1|IsHidden=T|Text=No SVHC|Name=REACH SVHC
|RECORD=41|OwnerIndex=568|IndexInSheet=9|OwnerPartId=-1|Location.X=597|Location.Y=262|Color=8388608|FontID=1|IsHidden=T|Text=0.063 inch|Name=Width
|RECORD=41|OwnerIndex=568|IndexInSheet=10|OwnerPartId=-1|Location.X=597|Location.Y=262|Color=8388608|FontID=1|IsHidden=T|Text=1205|Name=Case\Package
|RECORD=41|OwnerIndex=568|IndexInSheet=11|OwnerPartId=-1|Location.X=597|Location.Y=262|Color=8388608|FontID=1|IsHidden=T|Text=0.126 inch|Name=Length
|RECORD=41|OwnerIndex=568|IndexInSheet=12|OwnerPartId=-1|Location.X=597|Location.Y=262|Color=8388608|FontID=1|IsHidden=T|Text=0.024 inch|Name=Height
|RECORD=41|OwnerIndex=568|IndexInSheet=13|OwnerPartId=-1|Location.X=597|Location.Y=262|Color=8388608|FontID=1|IsHidden=T|Text=Surface Mount|Name=Mount
|RECORD=41|OwnerIndex=568|IndexInSheet=14|OwnerPartId=-1|Location.X=597|Location.Y=262|Color=8388608|FontID=1|IsHidden=T|Text=1|Name=Package Quantity
|RECORD=41|OwnerIndex=568|IndexInSheet=15|OwnerPartId=-1|Location.X=597|Location.Y=262|Color=8388608|FontID=1|IsHidden=T|Text=Apr-15|Name=DatasheetVersion
|RECORD=41|OwnerIndex=568|IndexInSheet=16|OwnerPartId=-1|Location.X=597|Location.Y=262|Color=8388608|FontID=1|IsHidden=T|Text=Manufacturer URL|Name=ComponentLink1Description
|RECORD=41|OwnerIndex=568|IndexInSheet=17|OwnerPartId=-1|Location.X=597|Location.Y=262|Color=8388608|FontID=1|IsHidden=T|Text=-55 degC|Name=Min Operating Temperature
|RECORD=41|OwnerIndex=568|IndexInSheet=18|OwnerPartId=-1|Location.X=597|Location.Y=262|Color=8388608|FontID=1|IsHidden=T|Text=Tape and Reel|Name=Packaging
|RECORD=41|OwnerIndex=568|IndexInSheet=19|OwnerPartId=-1|Location.X=597|Location.Y=262|Color=8388608|FontID=1|IsHidden=T|Text=No|Name=Radiation Hardening
|RECORD=41|OwnerIndex=568|IndexInSheet=20|OwnerPartId=-1|Location.X=597|Location.Y=262|Color=8388608|FontID=6|IsHidden=T|Text=http://industrial.panasonic.com/cdbs/www-data/pdf/RDA0000/AOA0000C86.pdf|Name=ComponentLink2URL
|RECORD=41|OwnerIndex=568|IndexInSheet=21|OwnerPartId=-1|Location.X=597|Location.Y=262|Color=8388608|FontID=1|IsHidden=T|Text=3216|Name=Case Code (Metric)
|RECORD=41|OwnerIndex=568|IndexInSheet=22|OwnerPartId=-1|Location.X=597|Location.Y=262|Color=8388608|FontID=1|IsHidden=T|Text=8|Name=Pins
|RECORD=41|OwnerIndex=568|IndexInSheet=23|OwnerPartId=-1|Location.X=597|Location.Y=262|Color=8388608|FontID=1|IsHidden=T|Text=1206|Name=Case Code (Imperial)
|RECORD=41|OwnerIndex=568|IndexInSheet=24|OwnerPartId=-1|Location.X=597|Location.Y=262|Color=8388608|FontID=1|IsHidden=T|Text=Thick Film|Name=Type (Resistor)
|RECORD=41|OwnerIndex=568|IndexInSheet=25|OwnerPartId=-1|Location.X=597|Location.Y=262|Color=8388608|FontID=1|IsHidden=T|Text=true|Name=RoHSCompliant
|RECORD=41|OwnerIndex=568|IndexInSheet=26|OwnerPartId=-1|Location.X=597|Location.Y=262|Color=8388608|FontID=1|IsHidden=T|Text=5%|Name=Tolerance
|RECORD=41|OwnerIndex=568|IndexInSheet=27|OwnerPartId=-1|Location.X=597|Location.Y=262|Color=8388608|FontID=1|IsHidden=T|Text=Datasheet|Name=ComponentLink2Description
|RECORD=41|OwnerIndex=568|IndexInSheet=28|OwnerPartId=-1|Location.X=597|Location.Y=262|Color=8388608|FontID=1|IsHidden=T|Text=2-Pin Surface Mount Device, Body 1.6 x 0.85 mm|Name=PackageDescription
|RECORD=41|OwnerIndex=568|IndexInSheet=29|OwnerPartId=-1|Location.X=597|Location.Y=262|Color=8388608|FontID=6|IsHidden=T|Text=http://www.panasonic.com/|Name=ComponentLink1URL
|RECORD=41|OwnerIndex=568|IndexInSheet=30|OwnerPartId=-1|Location.X=597|Location.Y=262|Color=8388608|FontID=1|IsHidden=T|Text=250 mW|Name=Power Rating
|RECORD=34|OwnerIndex=568|IndexInSheet=-1|OwnerPartId=-1|Location.X=603|Location.Y=241|Color=8388608|FontID=1|Text=R41|Name=Designator|ReadOnlyState=1
|RECORD=41|OwnerIndex=568|IndexInSheet=-1|OwnerPartId=-1|Location.X=603|Location.Y=231|Color=8388608|FontID=1|Text=4.7K|Name=Comment
|RECORD=44|OwnerIndex=568
|RECORD=45|OwnerIndex=604|IndexInSheet=-1|Description=Chip Resistor, 2-Leads, Body 1.75x0.95mm, IPC Medium Density|UseComponentLibrary=T|ModelName=RESC1608X55X30NL15T15|ModelType=PCBLIB|DatafileCount=1|ModelDatafileEntity0=RESC1608X55X30NL15T15|ModelDatafileKind0=PCBLib|IsCurrent=T|DatalinksLocked=T|DatabaseDatalinksLocked=T
|RECORD=46|OwnerIndex=605
|RECORD=48|OwnerIndex=605
|RECORD=41|OwnerIndex=607|IndexInSheet=-1|OwnerPartId=-1|Color=8388608|FontID=1|IsHidden=T|Text=2D|Name=Available Preview Images
|RECORD=45|OwnerIndex=604|IndexInSheet=-1|Description=Chip Resistor, 2-Leads, Body 1.75x0.95mm, IPC Low Density|UseComponentLibrary=T|ModelName=RESC1608X55X30ML15T15|ModelType=PCBLIB|DatafileCount=1|ModelDatafileEntity0=RESC1608X55X30ML15T15|ModelDatafileKind0=PCBLib|DatalinksLocked=T|DatabaseDatalinksLocked=T
|RECORD=46|OwnerIndex=609
|RECORD=48|OwnerIndex=609
|RECORD=41|OwnerIndex=611|IndexInSheet=-1|OwnerPartId=-1|Color=8388608|FontID=1|IsHidden=T|Text=2D|Name=Available Preview Images
|RECORD=45|OwnerIndex=604|IndexInSheet=-1|Description=Chip Resistor, 2-Leads, Body 1.75x0.95mm, IPC High Density|UseComponentLibrary=T|ModelName=RESC1608X55X30LL15T15|ModelType=PCBLIB|DatafileCount=1|ModelDatafileEntity0=RESC1608X55X30LL15T15|ModelDatafileKind0=PCBLib|DatalinksLocked=T|DatabaseDatalinksLocked=T
|RECORD=46|OwnerIndex=613
|RECORD=48|OwnerIndex=613
|RECORD=41|OwnerIndex=615|IndexInSheet=-1|OwnerPartId=-1|Color=8388608|FontID=1|IsHidden=T|Text=2D|Name=Available Preview Images
|RECORD=17|IndexInSheet=71|OwnerPartId=-1|Style=4|ShowNetName=T|Location.X=600|Location.Y=200|Orientation=3|Color=128|FontID=1|Text=GND
|RECORD=41|IndexInSheet=72|OwnerPartId=-1|Color=8388608|FontID=1|IsHidden=T|Name=ConfigurationParameters|ReadOnlyState=1
|RECORD=41|IndexInSheet=73|OwnerPartId=-1|Color=8388608|FontID=1|IsHidden=T|Name=ConfiguratorName|ReadOnlyState=1
|RECORD=41|IndexInSheet=74|OwnerPartId=-1|Color=8388608|FontID=1|IsHidden=T|Name=VersionControl_RevNumber|ReadOnlyState=1
|RECORD=41|IndexInSheet=75|OwnerPartId=-1|Color=8388608|FontID=1|IsHidden=T|Name=IsUserConfigurable|ReadOnlyState=1
|RECORD=41|IndexInSheet=76|OwnerPartId=-1|Color=8388608|FontID=1|IsHidden=T|Name=VersionControl_ProjFolderRevNumber|ReadOnlyState=1
|RECORD=41|IndexInSheet=77|OwnerPartId=-1|Color=8388608|FontID=1|IsHidden=T|Name=SPICEModelCache|ReadOnlyState=1
|RECORD=1|LibReference=8706943c75ba83719d021d2fdc84c58|ComponentDescription=LED BLUE CLEAR CHIP SMD|PartCount=2|DisplayModeCount=1|IndexInSheet=78|OwnerPartId=-1|Location.X=700|Location.Y=900|Orientation=3|CurrentPartId=1|LibraryPath=*|SourceLibraryName=Altium Content Vault|TargetFileName=*|AreaColor=11599871|Color=128|PartIDLocked=T|DesignItemId=CMP-22017-000008-1|AllPinCount=2
|RECORD=2|OwnerIndex=624|OwnerPartId=1|Electrical=4|PinConglomerate=33|PinLength=20|Location.X=700|Location.Y=880|Name=A|Designator=2|PinPropagationDelay=0.000000E+000
|RECORD=2|OwnerIndex=624|OwnerPartId=1|Electrical=4|PinConglomerate=35|PinLength=20|Location.X=700|Location.Y=860|Name=C|Designator=1|PinPropagationDelay=0.000000E+000
|RECORD=13|OwnerIndex=624|IsNotAccesible=T|IndexInSheet=2|OwnerPartId=1|Location.X=710|Location.Y=880|Corner.X=690|Corner.Y=880|LineWidth=1|Color=16711680
|RECORD=13|OwnerIndex=624|IsNotAccesible=T|IndexInSheet=3|OwnerPartId=1|Location.X=710|Location.Y=860|Corner.X=690|Corner.Y=860|LineWidth=1|Color=16711680
|RECORD=13|OwnerIndex=624|IsNotAccesible=T|IndexInSheet=4|OwnerPartId=1|Location.X=710|Location.Y=880|Corner.X=700|Corner.Y=860|LineWidth=1|Color=16711680
|RECORD=13|OwnerIndex=624|IsNotAccesible=T|IndexInSheet=5|OwnerPartId=1|Location.X=690|Location.Y=880|Corner.X=700|Corner.Y=860|LineWidth=1|Color=16711680
|RECORD=13|OwnerIndex=624|IsNotAccesible=T|IndexInSheet=6|OwnerPartId=1|Location.X=712|Location.Y=875|Corner.X=722|Corner.Y=865|LineWidth=1|Color=16711680
|RECORD=13|OwnerIndex=624|IsNotAccesible=T|IndexInSheet=7|OwnerPartId=1|Location.X=722|Location.Y=865|Corner.X=722|Corner.Y=870|LineWidth=1|Color=16711680
|RECORD=13|OwnerIndex=624|IsNotAccesible=T|IndexInSheet=8|OwnerPartId=1|Location.X=722|Location.Y=865|Corner.X=717|Corner.Y=865|LineWidth=1|Color=16711680
|RECORD=13|OwnerIndex=624|IsNotAccesible=T|IndexInSheet=9|OwnerPartId=1|Location.X=708|Location.Y=868|Corner.X=718|Corner.Y=858|LineWidth=1|Color=16711680
|RECORD=13|OwnerIndex=624|IsNotAccesible=T|IndexInSheet=10|OwnerPartId=1|Location.X=718|Location.Y=858|Corner.X=718|Corner.Y=863|LineWidth=1|Color=16711680
|RECORD=13|OwnerIndex=624|IsNotAccesible=T|IndexInSheet=11|OwnerPartId=1|Location.X=718|Location.Y=858|Corner.X=713|Corner.Y=858|LineWidth=1|Color=16711680
|RECORD=13|OwnerIndex=624|IsNotAccesible=T|IndexInSheet=12|OwnerPartId=1|Location.X=700|Location.Y=880|Corner.X=700|Corner.Y=883|LineWidth=1|Color=16711680
|RECORD=13|OwnerIndex=624|IsNotAccesible=T|IndexInSheet=13|OwnerPartId=1|Location.X=700|Location.Y=860|Corner.X=700|Corner.Y=857|LineWidth=1|Color=16711680
|RECORD=41|OwnerIndex=624|IndexInSheet=14|OwnerPartId=-1|Location.X=689|Location.Y=902|Color=8388608|FontID=1|IsHidden=T|Text=Colorless|Name=Lens Color
|RECORD=41|OwnerIndex=624|IndexInSheet=15|OwnerPartId=-1|Location.X=689|Location.Y=902|Color=8388608|FontID=1|IsHidden=T|Text=1608|Name=Case Code (Metric)
|RECORD=41|OwnerIndex=624|IndexInSheet=16|OwnerPartId=-1|Location.X=689|Location.Y=902|Color=8388608|FontID=1|IsHidden=T|Text=Tape and Reel|Name=Packaging
|RECORD=41|OwnerIndex=624|IndexInSheet=17|OwnerPartId=-1|Location.X=689|Location.Y=902|Color=8388608|FontID=1|IsHidden=T|Text=0603|Name=Case/Package
|RECORD=41|OwnerIndex=624|IndexInSheet=18|OwnerPartId=-1|Location.X=689|Location.Y=902|Color=8388608|FontID=1|IsHidden=T|Text=1.6mm|Name=Depth
|RECORD=41|OwnerIndex=624|IndexInSheet=19|OwnerPartId=-1|Location.X=689|Location.Y=902|Color=8388608|FontID=1|IsHidden=T|Text=475nm|Name=Dominant Wavelength
|RECORD=41|OwnerIndex=624|IndexInSheet=20|OwnerPartId=-1|Location.X=689|Location.Y=902|Color=8388608|FontID=1|IsHidden=T|Text=Surface Mount|Name=Mount
|RECORD=41|OwnerIndex=624|IndexInSheet=21|OwnerPartId=-1|Location.X=689|Location.Y=902|Color=8388608|FontID=1|IsHidden=T|Text=20mA|Name=Forward Current
|RECORD=41|OwnerIndex=624|IndexInSheet=22|OwnerPartId=-1|Location.X=689|Location.Y=902|Color=8388608|FontID=1|IsHidden=T|Text=Lead Free|Name=Lead Free
|RECORD=41|OwnerIndex=624|IndexInSheet=23|OwnerPartId=-1|Location.X=689|Location.Y=902|Color=8388608|FontID=1|IsHidden=T|Text=468nm|Name=Wavelength
|RECORD=41|OwnerIndex=624|IndexInSheet=24|OwnerPartId=-1|Location.X=689|Location.Y=902|Color=8388608|FontID=1|IsHidden=T|Text=130°|Name=Viewing Angle
|RECORD=41|OwnerIndex=624|IndexInSheet=25|OwnerPartId=-1|Location.X=689|Location.Y=902|Color=8388608|FontID=1|IsHidden=T|Text=-20°C|Name=Min Operating Temperature
|RECORD=41|OwnerIndex=624|IndexInSheet=26|OwnerPartId=-1|Location.X=689|Location.Y=902|Color=8388608|FontID=1|IsHidden=T|Text=Clear|Name=Lens Transparency
|RECORD=41|OwnerIndex=624|IndexInSheet=27|OwnerPartId=-1|Location.X=689|Location.Y=902|Color=8388608|FontID=1|IsHidden=T|Text=76mW|Name=Power Dissipation
|RECORD=41|OwnerIndex=624|IndexInSheet=28|OwnerPartId=-1|Location.X=689|Location.Y=902|Color=8388608|FontID=1|IsHidden=T|Text=Blue|Name=Illumination Color
|RECORD=41|OwnerIndex=624|IndexInSheet=29|OwnerPartId=-1|Location.X=689|Location.Y=902|Color=8388608|FontID=1|IsHidden=T|Text=0.55mm|Name=Height
|RECORD=41|OwnerIndex=624|IndexInSheet=30|OwnerPartId=-1|Location.X=689|Location.Y=902|Color=8388608|FontID=1|IsHidden=T|Text=20mA|Name=Test Current
|RECORD=41|OwnerIndex=624|IndexInSheet=31|OwnerPartId=-1|Location.X=689|Location.Y=902|Color=8388608|FontID=1|IsHidden=T|Text=0603|Name=Case Code (Imperial)
|RECORD=41|OwnerIndex=624|IndexInSheet=32|OwnerPartId=-1|Location.X=689|Location.Y=902|Color=8388608|FontID=1|IsHidden=T|Text=180mcd|Name=Luminous Intensity
|RECORD=41|OwnerIndex=624|IndexInSheet=33|OwnerPartId=-1|Location.X=689|Location.Y=902|Color=8388608|FontID=1|IsHidden=T|Text=5V|Name=Reverse Voltage
|RECORD=41|OwnerIndex=624|IndexInSheet=34|OwnerPartId=-1|Location.X=689|Location.Y=902|Color=8388608|FontID=1|IsHidden=T|Text=80°C|Name=Max Operating Temperature
|RECORD=41|OwnerIndex=624|IndexInSheet=35|OwnerPartId=-1|Location.X=689|Location.Y=902|Color=8388608|FontID=1|IsHidden=T|Text=2|Name=Number of Pins
|RECORD=41|OwnerIndex=624|IndexInSheet=36|OwnerPartId=-1|Location.X=689|Location.Y=902|Color=8388608|FontID=1|IsHidden=T|Text=0.8mm|Name=Length
|RECORD=41|OwnerIndex=624|IndexInSheet=37|OwnerPartId=-1|Location.X=689|Location.Y=902|Color=8388608|FontID=1|IsHidden=T|Text=No|Name=Radiation Hardening
|RECORD=41|OwnerIndex=624|IndexInSheet=38|OwnerPartId=-1|Location.X=689|Location.Y=902|Color=8388608|FontID=1|IsHidden=T|Text=1|Name=Number of Elements
|RECORD=41|OwnerIndex=624|IndexInSheet=39|OwnerPartId=-1|Location.X=689|Location.Y=902|Color=8388608|FontID=1|IsHidden=T|Text=1|Name=Package Quantity
|RECORD=41|OwnerIndex=624|IndexInSheet=40|OwnerPartId=-1|Location.X=689|Location.Y=902|Color=8388608|FontID=1|IsHidden=T|Text=1|Name=Number of LEDs
|RECORD=41|OwnerIndex=624|IndexInSheet=41|OwnerPartId=-1|Location.X=689|Location.Y=902|Color=8388608|FontID=1|IsHidden=T|Text=Diffused|Name=Lens Style
|RECORD=41|OwnerIndex=624|IndexInSheet=42|OwnerPartId=-1|Location.X=689|Location.Y=902|Color=8388608|FontID=1|IsHidden=T|Text=3.8V|Name=Forward Voltage
|RECORD=41|OwnerIndex=624|IndexInSheet=43|OwnerPartId=-1|Location.X=689|Location.Y=902|Color=8388608|FontID=1|IsHidden=T|Text=0.8mm|Name=Width
|RECORD=41|OwnerIndex=624|IndexInSheet=44|OwnerPartId=-1|Location.X=689|Location.Y=902|Color=8388608|FontID=1|IsHidden=T|Text=75mW|Name=Max Power Dissipation
|RECORD=41|OwnerIndex=624|IndexInSheet=45|OwnerPartId=-1|Location.X=689|Location.Y=902|Color=8388608|FontID=1|IsHidden=T|Text=Blue|Name=Color
|RECORD=34|OwnerIndex=624|IndexInSheet=-1|OwnerPartId=-1|Location.X=723|Location.Y=874|Color=8388608|FontID=1|Text=D3|Name=Designator|ReadOnlyState=1
|RECORD=41|OwnerIndex=624|IndexInSheet=-1|OwnerPartId=1|Location.X=723|Location.Y=864|Color=8388608|FontID=1|Text=BLUE|Name=Comment
|RECORD=44|OwnerIndex=624
|RECORD=45|OwnerIndex=675|IndexInSheet=-1|UseComponentLibrary=T|ModelName=FP-LTST-C191TBKT-MFG|ModelType=PCBLIB|IsCurrent=T|DatalinksLocked=T|DatabaseDatalinksLocked=T
|RECORD=46|OwnerIndex=676
|RECORD=48|OwnerIndex=676
|RECORD=1|LibReference=8706943c75ba83719d021d2fdc84c58|ComponentDescription=LED BLUE CLEAR CHIP SMD|PartCount=2|DisplayModeCount=1|IndexInSheet=79|OwnerPartId=-1|Location.X=800|Location.Y=900|Orientation=3|CurrentPartId=1|LibraryPath=*|SourceLibraryName=Altium Content Vault|TargetFileName=*|AreaColor=11599871|Color=128|PartIDLocked=T|DesignItemId=CMP-22017-000008-1|AllPinCount=2
|RECORD=2|OwnerIndex=679|OwnerPartId=1|Electrical=4|PinConglomerate=33|PinLength=20|Location.X=800|Location.Y=880|Name=A|Designator=2|PinPropagationDelay=0.000000E+000
|RECORD=2|OwnerIndex=679|OwnerPartId=1|Electrical=4|PinConglomerate=35|PinLength=20|Location.X=800|Location.Y=860|Name=C|Designator=1|PinPropagationDelay=0.000000E+000
|RECORD=13|OwnerIndex=679|IsNotAccesible=T|IndexInSheet=2|OwnerPartId=1|Location.X=810|Location.Y=880|Corner.X=790|Corner.Y=880|LineWidth=1|Color=16711680
|RECORD=13|OwnerIndex=679|IsNotAccesible=T|IndexInSheet=3|OwnerPartId=1|Location.X=810|Location.Y=860|Corner.X=790|Corner.Y=860|LineWidth=1|Color=16711680
|RECORD=13|OwnerIndex=679|IsNotAccesible=T|IndexInSheet=4|OwnerPartId=1|Location.X=810|Location.Y=880|Corner.X=800|Corner.Y=860|LineWidth=1|Color=16711680
|RECORD=13|OwnerIndex=679|IsNotAccesible=T|IndexInSheet=5|OwnerPartId=1|Location.X=790|Location.Y=880|Corner.X=800|Corner.Y=860|LineWidth=1|Color=16711680
|RECORD=13|OwnerIndex=679|IsNotAccesible=T|IndexInSheet=6|OwnerPartId=1|Location.X=812|Location.Y=875|Corner.X=822|Corner.Y=865|LineWidth=1|Color=16711680
|RECORD=13|OwnerIndex=679|IsNotAccesible=T|IndexInSheet=7|OwnerPartId=1|Location.X=822|Location.Y=865|Corner.X=822|Corner.Y=870|LineWidth=1|Color=16711680
|RECORD=13|OwnerIndex=679|IsNotAccesible=T|IndexInSheet=8|OwnerPartId=1|Location.X=822|Location.Y=865|Corner.X=817|Corner.Y=865|LineWidth=1|Color=16711680
|RECORD=13|OwnerIndex=679|IsNotAccesible=T|IndexInSheet=9|OwnerPartId=1|Location.X=808|Location.Y=868|Corner.X=818|Corner.Y=858|LineWidth=1|Color=16711680
|RECORD=13|OwnerIndex=679|IsNotAccesible=T|IndexInSheet=10|OwnerPartId=1|Location.X=818|Location.Y=858|Corner.X=818|Corner.Y=863|LineWidth=1|Color=16711680
|RECORD=13|OwnerIndex=679|IsNotAccesible=T|IndexInSheet=11|OwnerPartId=1|Location.X=818|Location.Y=858|Corner.X=813|Corner.Y=858|LineWidth=1|Color=16711680
|RECORD=13|OwnerIndex=679|IsNotAccesible=T|IndexInSheet=12|OwnerPartId=1|Location.X=800|Location.Y=880|Corner.X=800|Corner.Y=883|LineWidth=1|Color=16711680
|RECORD=13|OwnerIndex=679|IsNotAccesible=T|IndexInSheet=13|OwnerPartId=1|Location.X=800|Location.Y=860|Corner.X=800|Corner.Y=857|LineWidth=1|Color=16711680
|RECORD=41|OwnerIndex=679|IndexInSheet=14|OwnerPartId=-1|Location.X=789|Location.Y=902|Color=8388608|FontID=1|IsHidden=T|Text=Colorless|Name=Lens Color
|RECORD=41|OwnerIndex=679|IndexInSheet=15|OwnerPartId=-1|Location.X=789|Location.Y=902|Color=8388608|FontID=1|IsHidden=T|Text=1608|Name=Case Code (Metric)
|RECORD=41|OwnerIndex=679|IndexInSheet=16|OwnerPartId=-1|Location.X=789|Location.Y=902|Color=8388608|FontID=1|IsHidden=T|Text=Tape and Reel|Name=Packaging
|RECORD=41|OwnerIndex=679|IndexInSheet=17|OwnerPartId=-1|Location.X=789|Location.Y=902|Color=8388608|FontID=1|IsHidden=T|Text=0603|Name=Case/Package
|RECORD=41|OwnerIndex=679|IndexInSheet=18|OwnerPartId=-1|Location.X=789|Location.Y=902|Color=8388608|FontID=1|IsHidden=T|Text=1.6mm|Name=Depth
|RECORD=41|OwnerIndex=679|IndexInSheet=19|OwnerPartId=-1|Location.X=789|Location.Y=902|Color=8388608|FontID=1|IsHidden=T|Text=475nm|Name=Dominant Wavelength
|RECORD=41|OwnerIndex=679|IndexInSheet=20|OwnerPartId=-1|Location.X=789|Location.Y=902|Color=8388608|FontID=1|IsHidden=T|Text=Surface Mount|Name=Mount
|RECORD=41|OwnerIndex=679|IndexInSheet=21|OwnerPartId=-1|Location.X=789|Location.Y=902|Color=8388608|FontID=1|IsHidden=T|Text=20mA|Name=Forward Current
|RECORD=41|OwnerIndex=679|IndexInSheet=22|OwnerPartId=-1|Location.X=789|Location.Y=902|Color=8388608|FontID=1|IsHidden=T|Text=Lead Free|Name=Lead Free
|RECORD=41|OwnerIndex=679|IndexInSheet=23|OwnerPartId=-1|Location.X=789|Location.Y=902|Color=8388608|FontID=1|IsHidden=T|Text=468nm|Name=Wavelength
|RECORD=41|OwnerIndex=679|IndexInSheet=24|OwnerPartId=-1|Location.X=789|Location.Y=902|Color=8388608|FontID=1|IsHidden=T|Text=130°|Name=Viewing Angle
|RECORD=41|OwnerIndex=679|IndexInSheet=25|OwnerPartId=-1|Location.X=789|Location.Y=902|Color=8388608|FontID=1|IsHidden=T|Text=-20°C|Name=Min Operating Temperature
|RECORD=41|OwnerIndex=679|IndexInSheet=26|OwnerPartId=-1|Location.X=789|Location.Y=902|Color=8388608|FontID=1|IsHidden=T|Text=Clear|Name=Lens Transparency
|RECORD=41|OwnerIndex=679|IndexInSheet=27|OwnerPartId=-1|Location.X=789|Location.Y=902|Color=8388608|FontID=1|IsHidden=T|Text=76mW|Name=Power Dissipation
|RECORD=41|OwnerIndex=679|IndexInSheet=28|OwnerPartId=-1|Location.X=789|Location.Y=902|Color=8388608|FontID=1|IsHidden=T|Text=Blue|Name=Illumination Color
|RECORD=41|OwnerIndex=679|IndexInSheet=29|OwnerPartId=-1|Location.X=789|Location.Y=902|Color=8388608|FontID=1|IsHidden=T|Text=0.55mm|Name=Height
|RECORD=41|OwnerIndex=679|IndexInSheet=30|OwnerPartId=-1|Location.X=789|Location.Y=902|Color=8388608|FontID=1|IsHidden=T|Text=20mA|Name=Test Current
|RECORD=41|OwnerIndex=679|IndexInSheet=31|OwnerPartId=-1|Location.X=789|Location.Y=902|Color=8388608|FontID=1|IsHidden=T|Text=0603|Name=Case Code (Imperial)
|RECORD=41|OwnerIndex=679|IndexInSheet=32|OwnerPartId=-1|Location.X=789|Location.Y=902|Color=8388608|FontID=1|IsHidden=T|Text=180mcd|Name=Luminous Intensity
|RECORD=41|OwnerIndex=679|IndexInSheet=33|OwnerPartId=-1|Location.X=789|Location.Y=902|Color=8388608|FontID=1|IsHidden=T|Text=5V|Name=Reverse Voltage
|RECORD=41|OwnerIndex=679|IndexInSheet=34|OwnerPartId=-1|Location.X=789|Location.Y=902|Color=8388608|FontID=1|IsHidden=T|Text=80°C|Name=Max Operating Temperature
|RECORD=41|OwnerIndex=679|IndexInSheet=35|OwnerPartId=-1|Location.X=789|Location.Y=902|Color=8388608|FontID=1|IsHidden=T|Text=2|Name=Number of Pins
|RECORD=41|OwnerIndex=679|IndexInSheet=36|OwnerPartId=-1|Location.X=789|Location.Y=902|Color=8388608|FontID=1|IsHidden=T|Text=0.8mm|Name=Length
|RECORD=41|OwnerIndex=679|IndexInSheet=37|OwnerPartId=-1|Location.X=789|Location.Y=902|Color=8388608|FontID=1|IsHidden=T|Text=No|Name=Radiation Hardening
|RECORD=41|OwnerIndex=679|IndexInSheet=38|OwnerPartId=-1|Location.X=789|Location.Y=902|Color=8388608|FontID=1|IsHidden=T|Text=1|Name=Number of Elements
|RECORD=41|OwnerIndex=679|IndexInSheet=39|OwnerPartId=-1|Location.X=789|Location.Y=902|Color=8388608|FontID=1|IsHidden=T|Text=1|Name=Package Quantity
|RECORD=41|OwnerIndex=679|IndexInSheet=40|OwnerPartId=-1|Location.X=789|Location.Y=902|Color=8388608|FontID=1|IsHidden=T|Text=1|Name=Number of LEDs
|RECORD=41|OwnerIndex=679|IndexInSheet=41|OwnerPartId=-1|Location.X=789|Location.Y=902|Color=8388608|FontID=1|IsHidden=T|Text=Diffused|Name=Lens Style
|RECORD=41|OwnerIndex=679|IndexInSheet=42|OwnerPartId=-1|Location.X=789|Location.Y=902|Color=8388608|FontID=1|IsHidden=T|Text=3.8V|Name=Forward Voltage
|RECORD=41|OwnerIndex=679|IndexInSheet=43|OwnerPartId=-1|Location.X=789|Location.Y=902|Color=8388608|FontID=1|IsHidden=T|Text=0.8mm|Name=Width
|RECORD=41|OwnerIndex=679|IndexInSheet=44|OwnerPartId=-1|Location.X=789|Location.Y=902|Color=8388608|FontID=1|IsHidden=T|Text=75mW|Name=Max Power Dissipation
|RECORD=41|OwnerIndex=679|IndexInSheet=45|OwnerPartId=-1|Location.X=789|Location.Y=902|Color=8388608|FontID=1|IsHidden=T|Text=Blue|Name=Color
|RECORD=34|OwnerIndex=679|IndexInSheet=-1|OwnerPartId=-1|Location.X=823|Location.Y=874|Color=8388608|FontID=1|Text=D9|Name=Designator|ReadOnlyState=1
|RECORD=41|OwnerIndex=679|IndexInSheet=-1|OwnerPartId=1|Location.X=823|Location.Y=864|Color=8388608|FontID=1|Text=BLUE|Name=Comment
|RECORD=44|OwnerIndex=679
|RECORD=45|OwnerIndex=730|IndexInSheet=-1|UseComponentLibrary=T|ModelName=FP-LTST-C191TBKT-MFG|ModelType=PCBLIB|IsCurrent=T|DatalinksLocked=T|DatabaseDatalinksLocked=T
|RECORD=46|OwnerIndex=731
|RECORD=48|OwnerIndex=731
|RECORD=1|LibReference=8706943c75ba83719d021d2fdc84c58|ComponentDescription=LED BLUE CLEAR CHIP SMD|PartCount=2|DisplayModeCount=1|IndexInSheet=80|OwnerPartId=-1|Location.X=900|Location.Y=900|Orientation=3|CurrentPartId=1|LibraryPath=*|SourceLibraryName=Altium Content Vault|TargetFileName=*|AreaColor=11599871|Color=128|PartIDLocked=T|DesignItemId=CMP-22017-000008-1|AllPinCount=2
|RECORD=2|OwnerIndex=734|OwnerPartId=1|Electrical=4|PinConglomerate=33|PinLength=20|Location.X=900|Location.Y=880|Name=A|Designator=2|PinPropagationDelay=0.000000E+000
|RECORD=2|OwnerIndex=734|OwnerPartId=1|Electrical=4|PinConglomerate=35|PinLength=20|Location.X=900|Location.Y=860|Name=C|Designator=1|PinPropagationDelay=0.000000E+000
|RECORD=13|OwnerIndex=734|IsNotAccesible=T|IndexInSheet=2|OwnerPartId=1|Location.X=910|Location.Y=880|Corner.X=890|Corner.Y=880|LineWidth=1|Color=16711680
|RECORD=13|OwnerIndex=734|IsNotAccesible=T|IndexInSheet=3|OwnerPartId=1|Location.X=910|Location.Y=860|Corner.X=890|Corner.Y=860|LineWidth=1|Color=16711680
|RECORD=13|OwnerIndex=734|IsNotAccesible=T|IndexInSheet=4|OwnerPartId=1|Location.X=910|Location.Y=880|Corner.X=900|Corner.Y=860|LineWidth=1|Color=16711680
|RECORD=13|OwnerIndex=734|IsNotAccesible=T|IndexInSheet=5|OwnerPartId=1|Location.X=890|Location.Y=880|Corner.X=900|Corner.Y=860|LineWidth=1|Color=16711680
|RECORD=13|OwnerIndex=734|IsNotAccesible=T|IndexInSheet=6|OwnerPartId=1|Location.X=912|Location.Y=875|Corner.X=922|Corner.Y=865|LineWidth=1|Color=16711680
|RECORD=13|OwnerIndex=734|IsNotAccesible=T|IndexInSheet=7|OwnerPartId=1|Location.X=922|Location.Y=865|Corner.X=922|Corner.Y=870|LineWidth=1|Color=16711680
|RECORD=13|OwnerIndex=734|IsNotAccesible=T|IndexInSheet=8|OwnerPartId=1|Location.X=922|Location.Y=865|Corner.X=917|Corner.Y=865|LineWidth=1|Color=16711680
|RECORD=13|OwnerIndex=734|IsNotAccesible=T|IndexInSheet=9|OwnerPartId=1|Location.X=908|Location.Y=868|Corner.X=918|Corner.Y=858|LineWidth=1|Color=16711680
|RECORD=13|OwnerIndex=734|IsNotAccesible=T|IndexInSheet=10|OwnerPartId=1|Location.X=918|Location.Y=858|Corner.X=918|Corner.Y=863|LineWidth=1|Color=16711680
|RECORD=13|OwnerIndex=734|IsNotAccesible=T|IndexInSheet=11|OwnerPartId=1|Location.X=918|Location.Y=858|Corner.X=913|Corner.Y=858|LineWidth=1|Color=16711680
|RECORD=13|OwnerIndex=734|IsNotAccesible=T|IndexInSheet=12|OwnerPartId=1|Location.X=900|Location.Y=880|Corner.X=900|Corner.Y=883|LineWidth=1|Color=16711680
|RECORD=13|OwnerIndex=734|IsNotAccesible=T|IndexInSheet=13|OwnerPartId=1|Location.X=900|Location.Y=860|Corner.X=900|Corner.Y=857|LineWidth=1|Color=16711680
|RECORD=41|OwnerIndex=734|IndexInSheet=14|OwnerPartId=-1|Location.X=889|Location.Y=902|Color=8388608|FontID=1|IsHidden=T|Text=Colorless|Name=Lens Color
|RECORD=41|OwnerIndex=734|IndexInSheet=15|OwnerPartId=-1|Location.X=889|Location.Y=902|Color=8388608|FontID=1|IsHidden=T|Text=1608|Name=Case Code (Metric)
|RECORD=41|OwnerIndex=734|IndexInSheet=16|OwnerPartId=-1|Location.X=889|Location.Y=902|Color=8388608|FontID=1|IsHidden=T|Text=Tape and Reel|Name=Packaging
|RECORD=41|OwnerIndex=734|IndexInSheet=17|OwnerPartId=-1|Location.X=889|Location.Y=902|Color=8388608|FontID=1|IsHidden=T|Text=0603|Name=Case/Package
|RECORD=41|OwnerIndex=734|IndexInSheet=18|OwnerPartId=-1|Location.X=889|Location.Y=902|Color=8388608|FontID=1|IsHidden=T|Text=1.6mm|Name=Depth
|RECORD=41|OwnerIndex=734|IndexInSheet=19|OwnerPartId=-1|Location.X=889|Location.Y=902|Color=8388608|FontID=1|IsHidden=T|Text=475nm|Name=Dominant Wavelength
|RECORD=41|OwnerIndex=734|IndexInSheet=20|OwnerPartId=-1|Location.X=889|Location.Y=902|Color=8388608|FontID=1|IsHidden=T|Text=Surface Mount|Name=Mount
|RECORD=41|OwnerIndex=734|IndexInSheet=21|OwnerPartId=-1|Location.X=889|Location.Y=902|Color=8388608|FontID=1|IsHidden=T|Text=20mA|Name=Forward Current
|RECORD=41|OwnerIndex=734|IndexInSheet=22|OwnerPartId=-1|Location.X=889|Location.Y=902|Color=8388608|FontID=1|IsHidden=T|Text=Lead Free|Name=Lead Free
|RECORD=41|OwnerIndex=734|IndexInSheet=23|OwnerPartId=-1|Location.X=889|Location.Y=902|Color=8388608|FontID=1|IsHidden=T|Text=468nm|Name=Wavelength
|RECORD=41|OwnerIndex=734|IndexInSheet=24|OwnerPartId=-1|Location.X=889|Location.Y=902|Color=8388608|FontID=1|IsHidden=T|Text=130°|Name=Viewing Angle
|RECORD=41|OwnerIndex=734|IndexInSheet=25|OwnerPartId=-1|Location.X=889|Location.Y=902|Color=8388608|FontID=1|IsHidden=T|Text=-20°C|Name=Min Operating Temperature
|RECORD=41|OwnerIndex=734|IndexInSheet=26|OwnerPartId=-1|Location.X=889|Location.Y=902|Color=8388608|FontID=1|IsHidden=T|Text=Clear|Name=Lens Transparency
|RECORD=41|OwnerIndex=734|IndexInSheet=27|OwnerPartId=-1|Location.X=889|Location.Y=902|Color=8388608|FontID=1|IsHidden=T|Text=76mW|Name=Power Dissipation
|RECORD=41|OwnerIndex=734|IndexInSheet=28|OwnerPartId=-1|Location.X=889|Location.Y=902|Color=8388608|FontID=1|IsHidden=T|Text=Blue|Name=Illumination Color
|RECORD=41|OwnerIndex=734|IndexInSheet=29|OwnerPartId=-1|Location.X=889|Location.Y=902|Color=8388608|FontID=1|IsHidden=T|Text=0.55mm|Name=Height
|RECORD=41|OwnerIndex=734|IndexInSheet=30|OwnerPartId=-1|Location.X=889|Location.Y=902|Color=8388608|FontID=1|IsHidden=T|Text=20mA|Name=Test Current
|RECORD=41|OwnerIndex=734|IndexInSheet=31|OwnerPartId=-1|Location.X=889|Location.Y=902|Color=8388608|FontID=1|IsHidden=T|Text=0603|Name=Case Code (Imperial)
|RECORD=41|OwnerIndex=734|IndexInSheet=32|OwnerPartId=-1|Location.X=889|Location.Y=902|Color=8388608|FontID=1|IsHidden=T|Text=180mcd|Name=Luminous Intensity
|RECORD=41|OwnerIndex=734|IndexInSheet=33|OwnerPartId=-1|Location.X=889|Location.Y=902|Color=8388608|FontID=1|IsHidden=T|Text=5V|Name=Reverse Voltage
|RECORD=41|OwnerIndex=734|IndexInSheet=34|OwnerPartId=-1|Location.X=889|Location.Y=902|Color=8388608|FontID=1|IsHidden=T|Text=80°C|Name=Max Operating Temperature
|RECORD=41|OwnerIndex=734|IndexInSheet=35|OwnerPartId=-1|Location.X=889|Location.Y=902|Color=8388608|FontID=1|IsHidden=T|Text=2|Name=Number of Pins
|RECORD=41|OwnerIndex=734|IndexInSheet=36|OwnerPartId=-1|Location.X=889|Location.Y=902|Color=8388608|FontID=1|IsHidden=T|Text=0.8mm|Name=Length
|RECORD=41|OwnerIndex=734|IndexInSheet=37|OwnerPartId=-1|Location.X=889|Location.Y=902|Color=8388608|FontID=1|IsHidden=T|Text=No|Name=Radiation Hardening
|RECORD=41|OwnerIndex=734|IndexInSheet=38|OwnerPartId=-1|Location.X=889|Location.Y=902|Color=8388608|FontID=1|IsHidden=T|Text=1|Name=Number of Elements
|RECORD=41|OwnerIndex=734|IndexInSheet=39|OwnerPartId=-1|Location.X=889|Location.Y=902|Color=8388608|FontID=1|IsHidden=T|Text=1|Name=Package Quantity
|RECORD=41|OwnerIndex=734|IndexInSheet=40|OwnerPartId=-1|Location.X=889|Location.Y=902|Color=8388608|FontID=1|IsHidden=T|Text=1|Name=Number of LEDs
|RECORD=41|OwnerIndex=734|IndexInSheet=41|OwnerPartId=-1|Location.X=889|Location.Y=902|Color=8388608|FontID=1|IsHidden=T|Text=Diffused|Name=Lens Style
|RECORD=41|OwnerIndex=734|IndexInSheet=42|OwnerPartId=-1|Location.X=889|Location.Y=902|Color=8388608|FontID=1|IsHidden=T|Text=3.8V|Name=Forward Voltage
|RECORD=41|OwnerIndex=734|IndexInSheet=43|OwnerPartId=-1|Location.X=889|Location.Y=902|Color=8388608|FontID=1|IsHidden=T|Text=0.8mm|Name=Width
|RECORD=41|OwnerIndex=734|IndexInSheet=44|OwnerPartId=-1|Location.X=889|Location.Y=902|Color=8388608|FontID=1|IsHidden=T|Text=75mW|Name=Max Power Dissipation
|RECORD=41|OwnerIndex=734|IndexInSheet=45|OwnerPartId=-1|Location.X=889|Location.Y=902|Color=8388608|FontID=1|IsHidden=T|Text=Blue|Name=Color
|RECORD=34|OwnerIndex=734|IndexInSheet=-1|OwnerPartId=-1|Location.X=923|Location.Y=874|Color=8388608|FontID=1|Text=D10|Name=Designator|ReadOnlyState=1
|RECORD=41|OwnerIndex=734|IndexInSheet=-1|OwnerPartId=1|Location.X=923|Location.Y=864|Color=8388608|FontID=1|Text=BLUE|Name=Comment
|RECORD=44|OwnerIndex=734
|RECORD=45|OwnerIndex=785|IndexInSheet=-1|UseComponentLibrary=T|ModelName=FP-LTST-C191TBKT-MFG|ModelType=PCBLIB|IsCurrent=T|DatalinksLocked=T|DatabaseDatalinksLocked=T
|RECORD=46|OwnerIndex=786
|RECORD=48|OwnerIndex=786
|RECORD=1|LibReference=8706943c75ba83719d021d2fdc84c58|ComponentDescription=LED BLUE CLEAR CHIP SMD|PartCount=2|DisplayModeCount=1|IndexInSheet=81|OwnerPartId=-1|Location.X=1000|Location.Y=900|Orientation=3|CurrentPartId=1|LibraryPath=*|SourceLibraryName=Altium Content Vault|TargetFileName=*|AreaColor=11599871|Color=128|PartIDLocked=T|DesignItemId=CMP-22017-000008-1|AllPinCount=2
|RECORD=2|OwnerIndex=789|OwnerPartId=1|Electrical=4|PinConglomerate=33|PinLength=20|Location.X=1000|Location.Y=880|Name=A|Designator=2|PinPropagationDelay=0.000000E+000
|RECORD=2|OwnerIndex=789|OwnerPartId=1|Electrical=4|PinConglomerate=35|PinLength=20|Location.X=1000|Location.Y=860|Name=C|Designator=1|PinPropagationDelay=0.000000E+000
|RECORD=13|OwnerIndex=789|IsNotAccesible=T|IndexInSheet=2|OwnerPartId=1|Location.X=1010|Location.Y=880|Corner.X=990|Corner.Y=880|LineWidth=1|Color=16711680
|RECORD=13|OwnerIndex=789|IsNotAccesible=T|IndexInSheet=3|OwnerPartId=1|Location.X=1010|Location.Y=860|Corner.X=990|Corner.Y=860|LineWidth=1|Color=16711680
|RECORD=13|OwnerIndex=789|IsNotAccesible=T|IndexInSheet=4|OwnerPartId=1|Location.X=1010|Location.Y=880|Corner.X=1000|Corner.Y=860|LineWidth=1|Color=16711680
|RECORD=13|OwnerIndex=789|IsNotAccesible=T|IndexInSheet=5|OwnerPartId=1|Location.X=990|Location.Y=880|Corner.X=1000|Corner.Y=860|LineWidth=1|Color=16711680
|RECORD=13|OwnerIndex=789|IsNotAccesible=T|IndexInSheet=6|OwnerPartId=1|Location.X=1012|Location.Y=875|Corner.X=1022|Corner.Y=865|LineWidth=1|Color=16711680
|RECORD=13|OwnerIndex=789|IsNotAccesible=T|IndexInSheet=7|OwnerPartId=1|Location.X=1022|Location.Y=865|Corner.X=1022|Corner.Y=870|LineWidth=1|Color=16711680
|RECORD=13|OwnerIndex=789|IsNotAccesible=T|IndexInSheet=8|OwnerPartId=1|Location.X=1022|Location.Y=865|Corner.X=1017|Corner.Y=865|LineWidth=1|Color=16711680
|RECORD=13|OwnerIndex=789|IsNotAccesible=T|IndexInSheet=9|OwnerPartId=1|Location.X=1008|Location.Y=868|Corner.X=1018|Corner.Y=858|LineWidth=1|Color=16711680
|RECORD=13|OwnerIndex=789|IsNotAccesible=T|IndexInSheet=10|OwnerPartId=1|Location.X=1018|Location.Y=858|Corner.X=1018|Corner.Y=863|LineWidth=1|Color=16711680
|RECORD=13|OwnerIndex=789|IsNotAccesible=T|IndexInSheet=11|OwnerPartId=1|Location.X=1018|Location.Y=858|Corner.X=1013|Corner.Y=858|LineWidth=1|Color=16711680
|RECORD=13|OwnerIndex=789|IsNotAccesible=T|IndexInSheet=12|OwnerPartId=1|Location.X=1000|Location.Y=880|Corner.X=1000|Corner.Y=883|LineWidth=1|Color=16711680
|RECORD=13|OwnerIndex=789|IsNotAccesible=T|IndexInSheet=13|OwnerPartId=1|Location.X=1000|Location.Y=860|Corner.X=1000|Corner.Y=857|LineWidth=1|Color=16711680
|RECORD=41|OwnerIndex=789|IndexInSheet=14|OwnerPartId=-1|Location.X=989|Location.Y=902|Color=8388608|FontID=1|IsHidden=T|Text=Colorless|Name=Lens Color
|RECORD=41|OwnerIndex=789|IndexInSheet=15|OwnerPartId=-1|Location.X=989|Location.Y=902|Color=8388608|FontID=1|IsHidden=T|Text=1608|Name=Case Code (Metric)
|RECORD=41|OwnerIndex=789|IndexInSheet=16|OwnerPartId=-1|Location.X=989|Location.Y=902|Color=8388608|FontID=1|IsHidden=T|Text=Tape and Reel|Name=Packaging
|RECORD=41|OwnerIndex=789|IndexInSheet=17|OwnerPartId=-1|Location.X=989|Location.Y=902|Color=8388608|FontID=1|IsHidden=T|Text=0603|Name=Case/Package
|RECORD=41|OwnerIndex=789|IndexInSheet=18|OwnerPartId=-1|Location.X=989|Location.Y=902|Color=8388608|FontID=1|IsHidden=T|Text=1.6mm|Name=Depth
|RECORD=41|OwnerIndex=789|IndexInSheet=19|OwnerPartId=-1|Location.X=989|Location.Y=902|Color=8388608|FontID=1|IsHidden=T|Text=475nm|Name=Dominant Wavelength
|RECORD=41|OwnerIndex=789|IndexInSheet=20|OwnerPartId=-1|Location.X=989|Location.Y=902|Color=8388608|FontID=1|IsHidden=T|Text=Surface Mount|Name=Mount
|RECORD=41|OwnerIndex=789|IndexInSheet=21|OwnerPartId=-1|Location.X=989|Location.Y=902|Color=8388608|FontID=1|IsHidden=T|Text=20mA|Name=Forward Current
|RECORD=41|OwnerIndex=789|IndexInSheet=22|OwnerPartId=-1|Location.X=989|Location.Y=902|Color=8388608|FontID=1|IsHidden=T|Text=Lead Free|Name=Lead Free
|RECORD=41|OwnerIndex=789|IndexInSheet=23|OwnerPartId=-1|Location.X=989|Location.Y=902|Color=8388608|FontID=1|IsHidden=T|Text=468nm|Name=Wavelength
|RECORD=41|OwnerIndex=789|IndexInSheet=24|OwnerPartId=-1|Location.X=989|Location.Y=902|Color=8388608|FontID=1|IsHidden=T|Text=130°|Name=Viewing Angle
|RECORD=41|OwnerIndex=789|IndexInSheet=25|OwnerPartId=-1|Location.X=989|Location.Y=902|Color=8388608|FontID=1|IsHidden=T|Text=-20°C|Name=Min Operating Temperature
|RECORD=41|OwnerIndex=789|IndexInSheet=26|OwnerPartId=-1|Location.X=989|Location.Y=902|Color=8388608|FontID=1|IsHidden=T|Text=Clear|Name=Lens Transparency
|RECORD=41|OwnerIndex=789|IndexInSheet=27|OwnerPartId=-1|Location.X=989|Location.Y=902|Color=8388608|FontID=1|IsHidden=T|Text=76mW|Name=Power Dissipation
|RECORD=41|OwnerIndex=789|IndexInSheet=28|OwnerPartId=-1|Location.X=989|Location.Y=902|Color=8388608|FontID=1|IsHidden=T|Text=Blue|Name=Illumination Color
|RECORD=41|OwnerIndex=789|IndexInSheet=29|OwnerPartId=-1|Location.X=989|Location.Y=902|Color=8388608|FontID=1|IsHidden=T|Text=0.55mm|Name=Height
|RECORD=41|OwnerIndex=789|IndexInSheet=30|OwnerPartId=-1|Location.X=989|Location.Y=902|Color=8388608|FontID=1|IsHidden=T|Text=20mA|Name=Test Current
|RECORD=41|OwnerIndex=789|IndexInSheet=31|OwnerPartId=-1|Location.X=989|Location.Y=902|Color=8388608|FontID=1|IsHidden=T|Text=0603|Name=Case Code (Imperial)
|RECORD=41|OwnerIndex=789|IndexInSheet=32|OwnerPartId=-1|Location.X=989|Location.Y=902|Color=8388608|FontID=1|IsHidden=T|Text=180mcd|Name=Luminous Intensity
|RECORD=41|OwnerIndex=789|IndexInSheet=33|OwnerPartId=-1|Location.X=989|Location.Y=902|Color=8388608|FontID=1|IsHidden=T|Text=5V|Name=Reverse Voltage
|RECORD=41|OwnerIndex=789|IndexInSheet=34|OwnerPartId=-1|Location.X=989|Location.Y=902|Color=8388608|FontID=1|IsHidden=T|Text=80°C|Name=Max Operating Temperature
|RECORD=41|OwnerIndex=789|IndexInSheet=35|OwnerPartId=-1|Location.X=989|Location.Y=902|Color=8388608|FontID=1|IsHidden=T|Text=2|Name=Number of Pins
|RECORD=41|OwnerIndex=789|IndexInSheet=36|OwnerPartId=-1|Location.X=989|Location.Y=902|Color=8388608|FontID=1|IsHidden=T|Text=0.8mm|Name=Length
|RECORD=41|OwnerIndex=789|IndexInSheet=37|OwnerPartId=-1|Location.X=989|Location.Y=902|Color=8388608|FontID=1|IsHidden=T|Text=No|Name=Radiation Hardening
|RECORD=41|OwnerIndex=789|IndexInSheet=38|OwnerPartId=-1|Location.X=989|Location.Y=902|Color=8388608|FontID=1|IsHidden=T|Text=1|Name=Number of Elements
|RECORD=41|OwnerIndex=789|IndexInSheet=39|OwnerPartId=-1|Location.X=989|Location.Y=902|Color=8388608|FontID=1|IsHidden=T|Text=1|Name=Package Quantity
|RECORD=41|OwnerIndex=789|IndexInSheet=40|OwnerPartId=-1|Location.X=989|Location.Y=902|Color=8388608|FontID=1|IsHidden=T|Text=1|Name=Number of LEDs
|RECORD=41|OwnerIndex=789|IndexInSheet=41|OwnerPartId=-1|Location.X=989|Location.Y=902|Color=8388608|FontID=1|IsHidden=T|Text=Diffused|Name=Lens Style
|RECORD=41|OwnerIndex=789|IndexInSheet=42|OwnerPartId=-1|Location.X=989|Location.Y=902|Color=8388608|FontID=1|IsHidden=T|Text=3.8V|Name=Forward Voltage
|RECORD=41|OwnerIndex=789|IndexInSheet=43|OwnerPartId=-1|Location.X=989|Location.Y=902|Color=8388608|FontID=1|IsHidden=T|Text=0.8mm|Name=Width
|RECORD=41|OwnerIndex=789|IndexInSheet=44|OwnerPartId=-1|Location.X=989|Location.Y=902|Color=8388608|FontID=1|IsHidden=T|Text=75mW|Name=Max Power Dissipation
|RECORD=41|OwnerIndex=789|IndexInSheet=45|OwnerPartId=-1|Location.X=989|Location.Y=902|Color=8388608|FontID=1|IsHidden=T|Text=Blue|Name=Color
|RECORD=34|OwnerIndex=789|IndexInSheet=-1|OwnerPartId=-1|Location.X=1023|Location.Y=874|Color=8388608|FontID=1|Text=D11|Name=Designator|ReadOnlyState=1
|RECORD=41|OwnerIndex=789|IndexInSheet=-1|OwnerPartId=1|Location.X=1023|Location.Y=864|Color=8388608|FontID=1|Text=BLUE|Name=Comment
|RECORD=44|OwnerIndex=789
|RECORD=45|OwnerIndex=840|IndexInSheet=-1|UseComponentLibrary=T|ModelName=FP-LTST-C191TBKT-MFG|ModelType=PCBLIB|IsCurrent=T|DatalinksLocked=T|DatabaseDatalinksLocked=T
|RECORD=46|OwnerIndex=841
|RECORD=48|OwnerIndex=841
|RECORD=27|IndexInSheet=82|OwnerPartId=-1|LineWidth=1|Color=8388608|LocationCount=2|X1=700|Y1=840|X2=700|Y2=830
|RECORD=27|IndexInSheet=83|OwnerPartId=-1|LineWidth=1|Color=8388608|LocationCount=2|X1=800|Y1=840|X2=800|Y2=830
|RECORD=27|IndexInSheet=84|OwnerPartId=-1|LineWidth=1|Color=8388608|LocationCount=2|X1=900|Y1=840|X2=900|Y2=830
|RECORD=27|IndexInSheet=85|OwnerPartId=-1|LineWidth=1|Color=8388608|LocationCount=2|X1=1000|Y1=840|X2=1000|Y2=830
|RECORD=27|IndexInSheet=86|OwnerPartId=-1|LineWidth=1|Color=8388608|LocationCount=3|X1=700|Y1=790|X2=700|Y2=770|X3=690|Y3=770
|RECORD=27|IndexInSheet=87|OwnerPartId=-1|LineWidth=1|Color=8388608|LocationCount=3|X1=800|Y1=790|X2=800|Y2=770|X3=790|Y3=770
|RECORD=27|IndexInSheet=88|OwnerPartId=-1|LineWidth=1|Color=8388608|LocationCount=3|X1=900|Y1=790|X2=900|Y2=770|X3=890|Y3=770
|RECORD=27|IndexInSheet=89|OwnerPartId=-1|LineWidth=1|Color=8388608|LocationCount=3|X1=1000|Y1=790|X2=1000|Y2=770|X3=990|Y3=770
|RECORD=27|IndexInSheet=90|OwnerPartId=-1|LineWidth=1|Color=8388608|LocationCount=4|X1=1150|Y1=550|X2=870|Y2=550|X3=870|Y3=490|X4=830|Y4=490
|RECORD=27|IndexInSheet=91|OwnerPartId=-1|LineWidth=1|Color=8388608|LocationCount=4|X1=830|Y1=480|X2=880|Y2=480|X3=880|Y3=540|X4=1150|Y4=540
|RECORD=27|IndexInSheet=92|OwnerPartId=-1|LineWidth=1|Color=8388608|LocationCount=4|X1=1150|Y1=530|X2=890|Y2=530|X3=890|Y3=470|X4=830|Y4=470
|RECORD=27|IndexInSheet=93|OwnerPartId=-1|LineWidth=1|Color=8388608|LocationCount=4|X1=830|Y1=450|X2=920|Y2=450|X3=920|Y3=490|X4=1150|Y4=490
|RECORD=27|IndexInSheet=94|OwnerPartId=-1|LineWidth=1|Color=8388608|LocationCount=4|X1=1150|Y1=480|X2=930|Y2=480|X3=930|Y3=440|X4=830|Y4=440
|RECORD=27|IndexInSheet=95|OwnerPartId=-1|LineWidth=1|Color=8388608|LocationCount=4|X1=830|Y1=430|X2=940|Y2=430|X3=940|Y3=470|X4=1150|Y4=470
|RECORD=27|IndexInSheet=96|OwnerPartId=-1|LineWidth=1|Color=8388608|LocationCount=4|X1=1150|Y1=430|X2=980|Y2=430|X3=980|Y3=410|X4=830|Y4=410
|RECORD=27|IndexInSheet=97|OwnerPartId=-1|LineWidth=1|Color=8388608|LocationCount=4|X1=830|Y1=400|X2=990|Y2=400|X3=990|Y3=420|X4=1150|Y4=420
|RECORD=27|IndexInSheet=98|OwnerPartId=-1|LineWidth=1|Color=8388608|LocationCount=4|X1=1150|Y1=410|X2=1000|Y2=410|X3=1000|Y3=390|X4=830|Y4=390
|RECORD=27|IndexInSheet=99|OwnerPartId=-1|LineWidth=1|Color=8388608|LocationCount=2|X1=830|Y1=370|X2=1150|Y2=370
|RECORD=27|IndexInSheet=100|OwnerPartId=-1|LineWidth=1|Color=8388608|LocationCount=2|X1=1150|Y1=360|X2=830|Y2=360
|RECORD=27|IndexInSheet=101|OwnerPartId=-1|LineWidth=1|Color=8388608|LocationCount=2|X1=830|Y1=350|X2=1150|Y2=350
|RECORD=27|IndexInSheet=102|OwnerPartId=-1|LineWidth=1|Color=8388608|LocationCount=4|X1=1150|Y1=300|X2=1000|Y2=300|X3=1000|Y3=330|X4=830|Y4=330
|RECORD=27|IndexInSheet=103|OwnerPartId=-1|LineWidth=1|Color=8388608|LocationCount=4|X1=830|Y1=320|X2=990|Y2=320|X3=990|Y3=290|X4=1150|Y4=290
|RECORD=27|IndexInSheet=104|OwnerPartId=-1|LineWidth=1|Color=8388608|LocationCount=4|X1=1150|Y1=280|X2=980|Y2=280|X3=980|Y3=310|X4=830|Y4=310
|RECORD=27|IndexInSheet=105|OwnerPartId=-1|LineWidth=1|Color=8388608|LocationCount=4|X1=830|Y1=290|X2=940|Y2=290|X3=940|Y3=230|X4=1150|Y4=230
|RECORD=27|IndexInSheet=106|OwnerPartId=-1|LineWidth=1|Color=8388608|LocationCount=4|X1=1150|Y1=220|X2=930|Y2=220|X3=930|Y3=280|X4=830|Y4=280
|RECORD=27|IndexInSheet=107|OwnerPartId=-1|LineWidth=1|Color=8388608|LocationCount=4|X1=830|Y1=270|X2=920|Y2=270|X3=920|Y3=210|X4=1150|Y4=210
|RECORD=27|IndexInSheet=108|OwnerPartId=-1|LineWidth=1|Color=8388608|LocationCount=2|X1=1250|Y1=300|X2=1280|Y2=300
|RECORD=27|IndexInSheet=109|OwnerPartId=-1|LineWidth=1|Color=8388608|LocationCount=2|X1=1250|Y1=370|X2=1280|Y2=370
|RECORD=27|IndexInSheet=110|OwnerPartId=-1|LineWidth=1|Color=8388608|LocationCount=2|X1=1250|Y1=430|X2=1280|Y2=430
|RECORD=27|IndexInSheet=111|OwnerPartId=-1|LineWidth=1|Color=8388608|LocationCount=2|X1=1250|Y1=490|X2=1280|Y2=490
|RECORD=27|IndexInSheet=112|OwnerPartId=-1|LineWidth=1|Color=8388608|LocationCount=2|X1=1250|Y1=550|X2=1280|Y2=550
|RECORD=27|IndexInSheet=113|OwnerPartId=-1|LineWidth=1|Color=8388608|LocationCount=8|X1=1280|Y1=600|X2=1280|Y2=550|X3=1280|Y3=490|X4=1280|Y4=430|X5=1280|Y5=370|X6=1280|Y6=300|X7=1280|Y7=230|X8=1250|Y8=230
|RECORD=27|IndexInSheet=114|OwnerPartId=-1|LineWidth=1|Color=8388608|LocationCount=2|X1=540|Y1=250|X2=540|Y2=340
|RECORD=27|IndexInSheet=115|OwnerPartId=-1|LineWidth=1|Color=8388608|LocationCount=2|X1=540|Y1=220|X2=540|Y2=200
|RECORD=27|IndexInSheet=116|OwnerPartId=-1|LineWidth=1|Color=8388608|LocationCount=2|X1=500|Y1=230|X2=500|Y2=200
|RECORD=27|IndexInSheet=117|OwnerPartId=-1|LineWidth=1|Color=8388608|LocationCount=3|X1=680|Y1=270|X2=650|Y2=270|X3=650|Y3=200
|RECORD=27|IndexInSheet=118|OwnerPartId=-1|LineWidth=1|Color=8388608|LocationCount=3|X1=680|Y1=280|X2=650|Y2=280|X3=650|Y3=270
|RECORD=27|IndexInSheet=119|OwnerPartId=-1|LineWidth=1|Color=8388608|LocationCount=3|X1=680|Y1=290|X2=650|Y2=290|X3=650|Y3=280
|RECORD=27|IndexInSheet=120|OwnerPartId=-1|LineWidth=1|Color=8388608|LocationCount=3|X1=680|Y1=300|X2=650|Y2=300|X3=650|Y3=290
|RECORD=27|IndexInSheet=121|OwnerPartId=-1|LineWidth=1|Color=8388608|LocationCount=3|X1=680|Y1=310|X2=650|Y2=310|X3=650|Y3=300
|RECORD=27|IndexInSheet=122|OwnerPartId=-1|LineWidth=1|Color=8388608|LocationCount=3|X1=440|Y1=430|X2=400|Y2=430|X3=400|Y3=280
|RECORD=27|IndexInSheet=123|OwnerPartId=-1|LineWidth=1|Color=8388608|LocationCount=2|X1=440|Y1=220|X2=440|Y2=200
|RECORD=27|IndexInSheet=124|OwnerPartId=-1|LineWidth=1|Color=8388608|LocationCount=2|X1=400|Y1=210|X2=400|Y2=200
|RECORD=27|IndexInSheet=125|OwnerPartId=-1|LineWidth=1|Color=8388608|LocationCount=2|X1=500|Y1=340|X2=500|Y2=510
|RECORD=27|IndexInSheet=126|OwnerPartId=-1|LineWidth=1|Color=8388608|LocationCount=2|X1=680|Y1=490|X2=580|Y2=490
|RECORD=27|IndexInSheet=127|OwnerPartId=-1|LineWidth=1|Color=8388608|LocationCount=2|X1=680|Y1=480|X2=580|Y2=480
|RECORD=27|IndexInSheet=128|OwnerPartId=-1|LineWidth=1|Color=8388608|LocationCount=3|X1=680|Y1=430|X2=440|Y2=430|X3=440|Y3=250
|RECORD=27|IndexInSheet=129|OwnerPartId=-1|LineWidth=1|Color=8388608|LocationCount=4|X1=680|Y1=340|X2=540|Y2=340|X3=500|Y3=340|X4=500|Y4=250
|RECORD=27|IndexInSheet=130|OwnerPartId=-1|LineWidth=1|Color=8388608|LocationCount=3|X1=680|Y1=460|X2=530|Y2=460|X3=530|Y3=510
|RECORD=27|IndexInSheet=131|OwnerPartId=-1|LineWidth=1|Color=8388608|LocationCount=3|X1=680|Y1=410|X2=600|Y2=410|X3=600|Y3=260
|RECORD=27|IndexInSheet=132|OwnerPartId=-1|LineWidth=1|Color=8388608|LocationCount=2|X1=600|Y1=220|X2=600|Y2=200
|RECORD=27|IndexInSheet=133|OwnerPartId=-1|LineWidth=1|Color=8388608|LocationCount=2|X1=800|Y1=900|X2=800|Y2=930
|RECORD=27|IndexInSheet=134|OwnerPartId=-1|LineWidth=1|Color=8388608|LocationCount=2|X1=900|Y1=900|X2=900|Y2=930
|RECORD=27|IndexInSheet=135|OwnerPartId=-1|LineWidth=1|Color=8388608|LocationCount=2|X1=1000|Y1=900|X2=1000|Y2=930
|RECORD=27|IndexInSheet=136|OwnerPartId=-1|LineWidth=1|Color=8388608|LocationCount=2|X1=700|Y1=925|X2=700|Y2=900
|RECORD=29|IndexInSheet=-1|OwnerPartId=-1|Location.X=440|Location.Y=430|Color=128
|RECORD=29|IndexInSheet=-1|OwnerPartId=-1|Location.X=500|Location.Y=340|Color=128
|RECORD=29|IndexInSheet=-1|OwnerPartId=-1|Location.X=540|Location.Y=340|Color=128
|RECORD=29|IndexInSheet=-1|OwnerPartId=-1|Location.X=650|Location.Y=270|Color=128
|RECORD=29|IndexInSheet=-1|OwnerPartId=-1|Location.X=650|Location.Y=280|Color=128
|RECORD=29|IndexInSheet=-1|OwnerPartId=-1|Location.X=650|Location.Y=290|Color=128
|RECORD=29|IndexInSheet=-1|OwnerPartId=-1|Location.X=650|Location.Y=300|Color=128
|RECORD=29|IndexInSheet=-1|OwnerPartId=-1|Location.X=1280|Location.Y=300|Color=128
|RECORD=29|IndexInSheet=-1|OwnerPartId=-1|Location.X=1280|Location.Y=370|Color=128
|RECORD=29|IndexInSheet=-1|OwnerPartId=-1|Location.X=1280|Location.Y=430|Color=128
|RECORD=29|IndexInSheet=-1|OwnerPartId=-1|Location.X=1280|Location.Y=490|Color=128
|RECORD=29|IndexInSheet=-1|OwnerPartId=-1|Location.X=1280|Location.Y=550|Color=128